FILE_TYPE = MACRO_DRAWING;
SET COLOR_WIRE YELLOW;
SET COLOR_PROP ORANGE;
SET COLOR_DOT WHITE;
SET COLOR_ARC YELLOW;
SET COLOR_BODY GREEN;
SET COLOR_NOTE PURPLE;
SET PROP_DISPLAY VALUE;
SET PAGE_NUMBER P110;
FORCEADD UNIVERSAL_GND..1
(2175 650);
FORCEPROP 3 LASTPIN (2175 700) SIG_NAME GND\g
J 0
(2185 710);
DISPLAY 0.659574 (2185 710);
PAINT MONO (2185 710);
DISPLAY INVISIBLE (2185 710);
FORCEPROP 2 LAST ROOM IO_SLOT
J 1
(1950 725);
DISPLAY 0.744681 (1950 725);
FORCEPROP 2 LAST CDS_LIB pure_quanta_power
J 0
(2175 650);
DISPLAY INVISIBLE (2175 650);
FORCEPROP 1 LAST HDL_POWER GND
J 1
(2200 575);
DISPLAY 0.872340 (2200 575);
PAINT GREEN (2200 575);
DISPLAY INVISIBLE (2200 575);
FORCEPROP 1 LAST PATH I1
J 0
(2250 650);
DISPLAY 0.872340 (2250 650);
PAINT AQUA (2250 650);
DISPLAY INVISIBLE (2250 650);
FORCEADD UNIVERSAL_GND..1
(2375 2375);
FORCEPROP 3 LASTPIN (2375 2425) SIG_NAME GND\g
J 0
(2385 2435);
DISPLAY 0.659574 (2385 2435);
PAINT MONO (2385 2435);
DISPLAY INVISIBLE (2385 2435);
FORCEPROP 2 LAST ROOM IO_SLOT
J 1
(2250 2425);
DISPLAY 0.744681 (2250 2425);
FORCEPROP 2 LAST CDS_LIB pure_quanta_power
J 0
(2375 2375);
DISPLAY INVISIBLE (2375 2375);
FORCEPROP 1 LAST HDL_POWER GND
J 1
(2400 2300);
DISPLAY 0.872340 (2400 2300);
PAINT GREEN (2400 2300);
DISPLAY INVISIBLE (2400 2300);
FORCEPROP 1 LAST PATH I10
J 0
(2450 2375);
DISPLAY 0.872340 (2450 2375);
PAINT AQUA (2450 2375);
DISPLAY INVISIBLE (2450 2375);
FORCEADD UNIVERSAL_GND..1
(2850 2375);
FORCEPROP 3 LASTPIN (2850 2425) SIG_NAME GND\g
J 0
(2860 2435);
DISPLAY 0.659574 (2860 2435);
PAINT MONO (2860 2435);
DISPLAY INVISIBLE (2860 2435);
FORCEPROP 2 LAST ROOM IO_SLOT
J 1
(2725 2400);
DISPLAY 0.744681 (2725 2400);
FORCEPROP 2 LAST CDS_LIB pure_quanta_power
J 0
(2850 2375);
DISPLAY INVISIBLE (2850 2375);
FORCEPROP 1 LAST HDL_POWER GND
J 1
(2875 2300);
DISPLAY 0.872340 (2875 2300);
PAINT GREEN (2875 2300);
DISPLAY INVISIBLE (2875 2300);
FORCEPROP 1 LAST PATH I11
J 0
(2925 2375);
DISPLAY 0.872340 (2925 2375);
PAINT AQUA (2925 2375);
DISPLAY INVISIBLE (2925 2375);
FORCEADD Q_RES..2
(2850 2700);
FORCEPROP 1 LAST LOCATION R3273
J 0
(2900 2750);
DISPLAY 0.978723 (2900 2750);
FORCEPROP 0 LAST $SEC 1
J 0
(2900 2875);
DISPLAY 0.680851 (2900 2875);
PAINT MONO (2900 2875);
DISPLAY INVISIBLE (2900 2875);
FORCEPROP 0 LAST CDS_SEC 1
J 0
(2900 2875);
DISPLAY 1.021277 (2900 2875);
DISPLAY INVISIBLE (2900 2875);
FORCEPROP 1 LASTPIN (2850 2800) $PN 1
J 0
(2855 2762);
DISPLAY 0.787234 (2855 2762);
PAINT MONO (2855 2762);
FORCEPROP 1 LASTPIN (2850 2600) $PN 2
J 0
(2855 2610);
DISPLAY 0.787234 (2855 2610);
PAINT MONO (2855 2610);
FORCEPROP 2 LAST ROOM PCIE REDRIVER BOM1
J 0
(2900 2825);
DISPLAY 0.361702 (2900 2825);
PAINT RED (2900 2825);
FORCEPROP 1 LAST VALUE 68K
J 0
(2900 2700);
DISPLAY 0.638298 (2900 2700);
FORCEPROP 1 LAST TOLERANCE 1%
J 0
(2900 2650);
DISPLAY 0.638298 (2900 2650);
FORCEPROP 1 LAST WATTAGE 1/16W
J 0
(2900 2600);
DISPLAY 0.638298 (2900 2600);
FORCEPROP 1 LAST MATERIAL EMPTY
J 0
(2900 2550);
DISPLAY 0.638298 (2900 2550);
PAINT RED (2900 2550);
FORCEPROP 1 LAST PACK_TYPE 0402LF
J 0
(2900 2450);
DISPLAY 0.638298 (2900 2450);
FORCEPROP 2 LAST CDS_LIB pure_quanta
J 0
(2850 2700);
DISPLAY INVISIBLE (2850 2700);
FORCEPROP 1 LAST PATH I12
J 0
(2900 2875);
DISPLAY 0.978723 (2900 2875);
PAINT WHITE (2900 2875);
DISPLAY INVISIBLE (2900 2875);
FORCEPROP 1 LAST PART_NUMBER CS36802FB04
J 0
(2900 2500);
DISPLAY 0.638298 (2900 2500);
DISPLAY INVISIBLE (2900 2500);
FORCEADD UNIVERSAL_POWER..1
(2375 3550);
FORCEPROP 3 LASTPIN (2375 3500) SIG_NAME P3V3_AUX\g
J 0
(2385 3510);
DISPLAY 0.659574 (2385 3510);
PAINT MONO (2385 3510);
DISPLAY INVISIBLE (2385 3510);
FORCEPROP 1 LAST HDL_POWER P3V3_AUX
J 1
(2375 3600);
DISPLAY 0.872340 (2375 3600);
PAINT GREEN (2375 3600);
FORCEPROP 2 LAST CDS_LIB pure_quanta_power
J 0
(2375 3550);
DISPLAY INVISIBLE (2375 3550);
FORCEPROP 1 LAST PATH I13
J 0
(2425 3575);
DISPLAY 0.872340 (2425 3575);
PAINT AQUA (2425 3575);
DISPLAY INVISIBLE (2425 3575);
FORCEADD Q_RES..2
(2375 3250);
FORCEPROP 1 LAST LOCATION R3269
J 0
(2425 3350);
DISPLAY 0.638298 (2425 3350);
FORCEPROP 0 LAST $SEC 1
J 0
(2425 3425);
DISPLAY 0.680851 (2425 3425);
PAINT MONO (2425 3425);
DISPLAY INVISIBLE (2425 3425);
FORCEPROP 0 LAST CDS_SEC 1
J 0
(2425 3425);
DISPLAY 1.021277 (2425 3425);
DISPLAY INVISIBLE (2425 3425);
FORCEPROP 1 LASTPIN (2375 3350) $PN 1
J 0
(2380 3312);
DISPLAY 0.787234 (2380 3312);
PAINT MONO (2380 3312);
FORCEPROP 1 LASTPIN (2375 3150) $PN 2
J 0
(2380 3160);
DISPLAY 0.787234 (2380 3160);
PAINT MONO (2380 3160);
FORCEPROP 2 LAST ROOM PCIE REDRIVER BOM1
J 0
(2425 3400);
DISPLAY 0.553191 (2425 3400);
PAINT RED (2425 3400);
FORCEPROP 1 LAST MATERIAL EMPTY
J 0
(2415 3175);
DISPLAY 0.638298 (2415 3175);
PAINT RED (2415 3175);
FORCEPROP 1 LAST PACK_TYPE 0402LF
J 0
(2415 3075);
DISPLAY 0.638298 (2415 3075);
FORCEPROP 1 LAST TOLERANCE 1%
J 0
(2420 3275);
DISPLAY 0.638298 (2420 3275);
FORCEPROP 1 LAST VALUE 1K
J 0
(2420 3325);
DISPLAY 0.638298 (2420 3325);
FORCEPROP 1 LAST WATTAGE 1/16W
J 0
(2415 3225);
DISPLAY 0.638298 (2415 3225);
FORCEPROP 2 LAST CDS_LIB pure_quanta
J 0
(2375 3250);
DISPLAY INVISIBLE (2375 3250);
FORCEPROP 1 LAST PATH I14
J 0
(2425 3425);
DISPLAY 0.978723 (2425 3425);
PAINT WHITE (2425 3425);
DISPLAY INVISIBLE (2425 3425);
FORCEPROP 1 LAST PART_NUMBER CS21002FB06
J 0
(2415 3125);
DISPLAY 0.638298 (2415 3125);
DISPLAY INVISIBLE (2415 3125);
FORCEADD UNIVERSAL_GND..1
(3025 650);
FORCEPROP 3 LASTPIN (3025 700) SIG_NAME GND\g
J 0
(3035 710);
DISPLAY 0.659574 (3035 710);
PAINT MONO (3035 710);
DISPLAY INVISIBLE (3035 710);
FORCEPROP 2 LAST ROOM IO_SLOT
J 1
(2800 725);
DISPLAY 0.744681 (2800 725);
FORCEPROP 2 LAST CDS_LIB pure_quanta_power
J 0
(3025 650);
DISPLAY INVISIBLE (3025 650);
FORCEPROP 1 LAST HDL_POWER GND
J 1
(3050 575);
DISPLAY 0.872340 (3050 575);
PAINT GREEN (3050 575);
DISPLAY INVISIBLE (3050 575);
FORCEPROP 1 LAST PATH I15
J 0
(3100 650);
DISPLAY 0.872340 (3100 650);
PAINT AQUA (3100 650);
DISPLAY INVISIBLE (3100 650);
FORCEADD Q_RES..2
(3025 975);
FORCEPROP 1 LAST LOCATION R3274
J 0
(3070 1100);
DISPLAY 0.978723 (3070 1100);
FORCEPROP 0 LAST $SEC 1
J 0
(3075 1150);
DISPLAY 0.680851 (3075 1150);
PAINT MONO (3075 1150);
DISPLAY INVISIBLE (3075 1150);
FORCEPROP 0 LAST CDS_SEC 1
J 0
(3075 1150);
DISPLAY 1.021277 (3075 1150);
DISPLAY INVISIBLE (3075 1150);
FORCEPROP 1 LASTPIN (3025 1075) $PN 1
J 0
(3030 1037);
DISPLAY 0.787234 (3030 1037);
PAINT MONO (3030 1037);
FORCEPROP 1 LASTPIN (3025 875) $PN 2
J 0
(3030 885);
DISPLAY 0.787234 (3030 885);
PAINT MONO (3030 885);
FORCEPROP 2 LAST ROOM PCIE REDRIVER BOM1
J 0
(3075 1150);
DISPLAY 0.361702 (3075 1150);
PAINT RED (3075 1150);
FORCEPROP 1 LAST MATERIAL EMPTY
J 0
(3065 900);
DISPLAY 0.638298 (3065 900);
PAINT RED (3065 900);
FORCEPROP 1 LAST PACK_TYPE 0402LF
J 0
(3065 800);
DISPLAY 0.638298 (3065 800);
FORCEPROP 1 LAST VALUE 68K
J 0
(3070 1050);
DISPLAY 0.638298 (3070 1050);
FORCEPROP 1 LAST WATTAGE 1/16W
J 0
(3065 950);
DISPLAY 0.638298 (3065 950);
FORCEPROP 1 LAST TOLERANCE 1%
J 0
(3070 1000);
DISPLAY 0.638298 (3070 1000);
FORCEPROP 2 LAST CDS_LIB pure_quanta
J 0
(3025 975);
DISPLAY INVISIBLE (3025 975);
FORCEPROP 1 LAST PATH I16
J 0
(3075 1150);
DISPLAY 0.978723 (3075 1150);
PAINT WHITE (3075 1150);
DISPLAY INVISIBLE (3075 1150);
FORCEPROP 1 LAST PART_NUMBER CS36802FB04
J 0
(3065 850);
DISPLAY 0.638298 (3065 850);
DISPLAY INVISIBLE (3065 850);
FORCEADD UNIVERSAL_GND..1
(3425 650);
FORCEPROP 3 LASTPIN (3425 700) SIG_NAME GND\g
J 0
(3435 710);
DISPLAY 0.659574 (3435 710);
PAINT MONO (3435 710);
DISPLAY INVISIBLE (3435 710);
FORCEPROP 2 LAST ROOM IO_SLOT
J 1
(3200 725);
DISPLAY 0.744681 (3200 725);
FORCEPROP 2 LAST CDS_LIB pure_quanta_power
J 0
(3425 650);
DISPLAY INVISIBLE (3425 650);
FORCEPROP 1 LAST HDL_POWER GND
J 1
(3450 575);
DISPLAY 0.872340 (3450 575);
PAINT GREEN (3450 575);
DISPLAY INVISIBLE (3450 575);
FORCEPROP 1 LAST PATH I17
J 0
(3500 650);
DISPLAY 0.872340 (3500 650);
PAINT AQUA (3500 650);
DISPLAY INVISIBLE (3500 650);
FORCEADD Q_RES..2
(3425 950);
FORCEPROP 1 LAST LOCATION R3278
J 0
(3470 1075);
DISPLAY 0.978723 (3470 1075);
FORCEPROP 0 LAST $SEC 1
J 0
(3475 1125);
DISPLAY 0.680851 (3475 1125);
PAINT MONO (3475 1125);
DISPLAY INVISIBLE (3475 1125);
FORCEPROP 0 LAST CDS_SEC 1
J 0
(3475 1125);
DISPLAY 1.021277 (3475 1125);
DISPLAY INVISIBLE (3475 1125);
FORCEPROP 1 LASTPIN (3425 1050) $PN 1
J 0
(3430 1012);
DISPLAY 0.787234 (3430 1012);
PAINT MONO (3430 1012);
FORCEPROP 1 LASTPIN (3425 850) $PN 2
J 0
(3430 860);
DISPLAY 0.787234 (3430 860);
PAINT MONO (3430 860);
FORCEPROP 1 LAST MATERIAL CHIP
J 0
(3465 875);
DISPLAY 0.638298 (3465 875);
FORCEPROP 1 LAST WATTAGE 1/16W
J 0
(3465 925);
DISPLAY 0.638298 (3465 925);
FORCEPROP 1 LAST VALUE 1K
J 0
(3470 1025);
DISPLAY 0.638298 (3470 1025);
FORCEPROP 1 LAST PACK_TYPE 0402LF
J 0
(3465 775);
DISPLAY 0.638298 (3465 775);
FORCEPROP 2 LAST ROOM PCIE REDRIVER BOM1
J 0
(3475 1125);
DISPLAY 0.553191 (3475 1125);
PAINT RED (3475 1125);
FORCEPROP 1 LAST TOLERANCE 1%
J 0
(3470 975);
DISPLAY 0.638298 (3470 975);
FORCEPROP 2 LAST CDS_LIB pure_quanta
J 0
(3425 950);
DISPLAY INVISIBLE (3425 950);
FORCEPROP 1 LAST PATH I18
J 0
(3475 1125);
DISPLAY 0.978723 (3475 1125);
PAINT WHITE (3475 1125);
DISPLAY INVISIBLE (3475 1125);
FORCEPROP 1 LAST PART_NUMBER CS21002FB06
J 0
(3465 825);
DISPLAY 0.638298 (3465 825);
DISPLAY INVISIBLE (3465 825);
FORCEADD Q_RES..2
(3425 1525);
FORCEPROP 1 LAST LOCATION R3277
J 0
(3470 1650);
DISPLAY 0.978723 (3470 1650);
FORCEPROP 0 LAST $SEC 1
J 0
(3475 1700);
DISPLAY 0.680851 (3475 1700);
PAINT MONO (3475 1700);
DISPLAY INVISIBLE (3475 1700);
FORCEPROP 0 LAST CDS_SEC 1
J 0
(3475 1700);
DISPLAY 1.021277 (3475 1700);
DISPLAY INVISIBLE (3475 1700);
FORCEPROP 1 LASTPIN (3425 1625) $PN 1
J 0
(3430 1587);
DISPLAY 0.787234 (3430 1587);
PAINT MONO (3430 1587);
FORCEPROP 1 LASTPIN (3425 1425) $PN 2
J 0
(3430 1435);
DISPLAY 0.787234 (3430 1435);
PAINT MONO (3430 1435);
FORCEPROP 1 LAST PACK_TYPE 0402LF
J 0
(3465 1350);
DISPLAY 0.638298 (3465 1350);
FORCEPROP 2 LAST ROOM PCIE REDRIVER BOM1
J 0
(3475 1700);
DISPLAY 0.680851 (3475 1700);
PAINT RED (3475 1700);
FORCEPROP 1 LAST VALUE 1K
J 0
(3470 1600);
DISPLAY 0.638298 (3470 1600);
FORCEPROP 1 LAST TOLERANCE 1%
J 0
(3470 1550);
DISPLAY 0.638298 (3470 1550);
FORCEPROP 1 LAST MATERIAL EMPTY
J 0
(3465 1450);
DISPLAY 0.638298 (3465 1450);
PAINT RED (3465 1450);
FORCEPROP 1 LAST WATTAGE 1/16W
J 0
(3465 1500);
DISPLAY 0.638298 (3465 1500);
FORCEPROP 2 LAST CDS_LIB pure_quanta
J 0
(3425 1525);
DISPLAY INVISIBLE (3425 1525);
FORCEPROP 1 LAST PATH I19
J 0
(3475 1700);
DISPLAY 0.978723 (3475 1700);
PAINT WHITE (3475 1700);
DISPLAY INVISIBLE (3475 1700);
FORCEPROP 1 LAST PART_NUMBER CS21002FB06
J 0
(3465 1400);
DISPLAY 0.638298 (3465 1400);
DISPLAY INVISIBLE (3465 1400);
FORCEADD Q_RES..2
(2175 1000);
FORCEPROP 1 LAST LOCATION R3268
J 0
(2220 1125);
DISPLAY 0.638298 (2220 1125);
FORCEPROP 0 LAST $SEC 1
J 0
(2225 1175);
DISPLAY 0.680851 (2225 1175);
PAINT MONO (2225 1175);
DISPLAY INVISIBLE (2225 1175);
FORCEPROP 0 LAST CDS_SEC 1
J 0
(2225 1175);
DISPLAY 1.021277 (2225 1175);
DISPLAY INVISIBLE (2225 1175);
FORCEPROP 1 LASTPIN (2175 1100) $PN 1
J 0
(2180 1062);
DISPLAY 0.787234 (2180 1062);
PAINT MONO (2180 1062);
FORCEPROP 1 LASTPIN (2175 900) $PN 2
J 0
(2180 910);
DISPLAY 0.787234 (2180 910);
PAINT MONO (2180 910);
FORCEPROP 2 LAST ROOM PCIE REDRIVER BOM1
J 0
(2225 1175);
DISPLAY 0.361702 (2225 1175);
PAINT RED (2225 1175);
FORCEPROP 1 LAST WATTAGE 1/16W
J 0
(2215 975);
DISPLAY 0.638298 (2215 975);
FORCEPROP 1 LAST TOLERANCE 1%
J 0
(2220 1025);
DISPLAY 0.638298 (2220 1025);
FORCEPROP 1 LAST VALUE 68K
J 0
(2220 1075);
DISPLAY 0.638298 (2220 1075);
FORCEPROP 1 LAST PACK_TYPE 0402LF
J 0
(2215 825);
DISPLAY 0.638298 (2215 825);
FORCEPROP 1 LAST MATERIAL EMPTY
J 0
(2215 925);
DISPLAY 0.638298 (2215 925);
PAINT RED (2215 925);
FORCEPROP 2 LAST CDS_LIB pure_quanta
J 0
(2175 1000);
DISPLAY INVISIBLE (2175 1000);
FORCEPROP 1 LAST PATH I2
J 0
(2225 1175);
DISPLAY 0.978723 (2225 1175);
PAINT WHITE (2225 1175);
DISPLAY INVISIBLE (2225 1175);
FORCEPROP 1 LAST PART_NUMBER CS36802FB04
J 0
(2215 875);
DISPLAY 0.638298 (2215 875);
DISPLAY INVISIBLE (2215 875);
FORCEADD OFFPAGE..2
(3950 1275);
FORCEPROP 2 LAST $XR0 111 
J 0
(4139 1275);
DISPLAY 0.638298 (4139 1275);
PAINT MONO (4139 1275);
FORCEPROP 2 LAST CDS_LIB standard
J 0
(3950 1275);
DISPLAY INVISIBLE (3950 1275);
FORCEPROP 1 LAST OFFPAGE TRUE
J 0
(4275 1150);
DISPLAY 0.872340 (4275 1150);
PAINT GREEN (4275 1150);
DISPLAY INVISIBLE (4275 1150);
FORCEPROP 1 LAST COMMENT_BODY TRUE
J 0
(3905 1180);
DISPLAY 0.872340 (3905 1180);
PAINT GREEN (3905 1180);
DISPLAY INVISIBLE (3905 1180);
FORCEPROP 2 LAST PATH I20
J 0
(4150 1325);
DISPLAY 0.680851 (4150 1325);
DISPLAY INVISIBLE (4150 1325);
FORCEADD OFFPAGE..2
(3950 1225);
FORCEPROP 2 LAST $XR0 111 
J 0
(4139 1225);
DISPLAY 0.638298 (4139 1225);
PAINT MONO (4139 1225);
FORCEPROP 2 LAST CDS_LIB standard
J 0
(3950 1225);
DISPLAY INVISIBLE (3950 1225);
FORCEPROP 1 LAST OFFPAGE TRUE
J 0
(4275 1100);
DISPLAY 0.872340 (4275 1100);
PAINT GREEN (4275 1100);
DISPLAY INVISIBLE (4275 1100);
FORCEPROP 1 LAST COMMENT_BODY TRUE
J 0
(3905 1130);
DISPLAY 0.872340 (3905 1130);
PAINT GREEN (3905 1130);
DISPLAY INVISIBLE (3905 1130);
FORCEPROP 2 LAST PATH I21
J 0
(4150 1275);
DISPLAY 0.680851 (4150 1275);
DISPLAY INVISIBLE (4150 1275);
FORCEADD Q_RES..2
(4425 975);
FORCEPROP 1 LAST LOCATION R3279
J 0
(4470 1100);
DISPLAY 0.638298 (4470 1100);
FORCEPROP 0 LAST $SEC 1
J 0
(4475 1150);
DISPLAY 0.680851 (4475 1150);
PAINT MONO (4475 1150);
DISPLAY INVISIBLE (4475 1150);
FORCEPROP 0 LAST CDS_SEC 1
J 0
(4475 1150);
DISPLAY 1.021277 (4475 1150);
DISPLAY INVISIBLE (4475 1150);
FORCEPROP 1 LASTPIN (4425 1075) $PN 1
J 0
(4430 1037);
DISPLAY 0.787234 (4430 1037);
PAINT MONO (4430 1037);
FORCEPROP 1 LASTPIN (4425 875) $PN 2
J 0
(4430 885);
DISPLAY 0.787234 (4430 885);
PAINT MONO (4430 885);
FORCEPROP 1 LAST MATERIAL EMPTY
J 0
(4465 900);
DISPLAY 0.638298 (4465 900);
PAINT RED (4465 900);
FORCEPROP 1 LAST VALUE 68K
J 0
(4470 1050);
DISPLAY 0.638298 (4470 1050);
FORCEPROP 1 LAST TOLERANCE 1%
J 0
(4470 1000);
DISPLAY 0.638298 (4470 1000);
FORCEPROP 1 LAST PACK_TYPE 0402LF
J 0
(4465 800);
DISPLAY 0.638298 (4465 800);
FORCEPROP 1 LAST WATTAGE 1/16W
J 0
(4465 950);
DISPLAY 0.638298 (4465 950);
FORCEPROP 2 LAST ROOM PCIE REDRIVER BOM1
J 0
(4475 1150);
DISPLAY 0.361702 (4475 1150);
PAINT RED (4475 1150);
FORCEPROP 2 LAST CDS_LIB pure_quanta
J 0
(4425 975);
DISPLAY INVISIBLE (4425 975);
FORCEPROP 1 LAST PATH I22
J 0
(4475 1150);
DISPLAY 0.978723 (4475 1150);
PAINT WHITE (4475 1150);
DISPLAY INVISIBLE (4475 1150);
FORCEPROP 1 LAST PART_NUMBER CS36802FB04
J 0
(4465 850);
DISPLAY 0.638298 (4465 850);
DISPLAY INVISIBLE (4465 850);
FORCEADD UNIVERSAL_GND..1
(4425 625);
FORCEPROP 3 LASTPIN (4425 675) SIG_NAME GND\g
J 0
(4435 685);
DISPLAY 0.659574 (4435 685);
PAINT MONO (4435 685);
DISPLAY INVISIBLE (4435 685);
FORCEPROP 2 LAST ROOM IO_SLOT
J 1
(4200 700);
DISPLAY 0.744681 (4200 700);
FORCEPROP 2 LAST CDS_LIB pure_quanta_power
J 0
(4425 625);
DISPLAY INVISIBLE (4425 625);
FORCEPROP 1 LAST HDL_POWER GND
J 1
(4450 550);
DISPLAY 0.872340 (4450 550);
PAINT GREEN (4450 550);
DISPLAY INVISIBLE (4450 550);
FORCEPROP 1 LAST PATH I23
J 0
(4500 625);
DISPLAY 0.872340 (4500 625);
PAINT AQUA (4500 625);
DISPLAY INVISIBLE (4500 625);
FORCEADD UNIVERSAL_GND..1
(4800 625);
FORCEPROP 3 LASTPIN (4800 675) SIG_NAME GND\g
J 0
(4810 685);
DISPLAY 0.659574 (4810 685);
PAINT MONO (4810 685);
DISPLAY INVISIBLE (4810 685);
FORCEPROP 2 LAST ROOM IO_SLOT
J 1
(4575 700);
DISPLAY 0.744681 (4575 700);
FORCEPROP 2 LAST CDS_LIB pure_quanta_power
J 0
(4800 625);
DISPLAY INVISIBLE (4800 625);
FORCEPROP 1 LAST HDL_POWER GND
J 1
(4825 550);
DISPLAY 0.872340 (4825 550);
PAINT GREEN (4825 550);
DISPLAY INVISIBLE (4825 550);
FORCEPROP 1 LAST PATH I24
J 0
(4875 625);
DISPLAY 0.872340 (4875 625);
PAINT AQUA (4875 625);
DISPLAY INVISIBLE (4875 625);
FORCEADD Q_RES..2
(4800 975);
FORCEPROP 1 LAST LOCATION R3281
J 0
(4845 1100);
DISPLAY 0.978723 (4845 1100);
FORCEPROP 0 LAST $SEC 1
J 0
(4850 1150);
DISPLAY 0.680851 (4850 1150);
PAINT MONO (4850 1150);
DISPLAY INVISIBLE (4850 1150);
FORCEPROP 0 LAST CDS_SEC 1
J 0
(4850 1150);
DISPLAY 1.021277 (4850 1150);
DISPLAY INVISIBLE (4850 1150);
FORCEPROP 1 LASTPIN (4800 1075) $PN 1
J 0
(4805 1037);
DISPLAY 0.787234 (4805 1037);
PAINT MONO (4805 1037);
FORCEPROP 1 LASTPIN (4800 875) $PN 2
J 0
(4805 885);
DISPLAY 0.787234 (4805 885);
PAINT MONO (4805 885);
FORCEPROP 2 LAST ROOM PCIE REDRIVER BOM1
J 0
(4850 1150);
DISPLAY 0.446809 (4850 1150);
PAINT RED (4850 1150);
FORCEPROP 1 LAST VALUE 1K
J 0
(4845 1050);
DISPLAY 0.638298 (4845 1050);
FORCEPROP 1 LAST TOLERANCE 1%
J 0
(4845 1000);
DISPLAY 0.638298 (4845 1000);
FORCEPROP 1 LAST PACK_TYPE 0402LF
J 0
(4840 800);
DISPLAY 0.638298 (4840 800);
FORCEPROP 1 LAST WATTAGE 1/16W
J 0
(4840 950);
DISPLAY 0.638298 (4840 950);
FORCEPROP 1 LAST MATERIAL EMPTY
J 0
(4840 900);
DISPLAY 0.638298 (4840 900);
PAINT RED (4840 900);
FORCEPROP 2 LAST CDS_LIB pure_quanta
J 0
(4800 975);
DISPLAY INVISIBLE (4800 975);
FORCEPROP 1 LAST PATH I25
J 0
(4850 1150);
DISPLAY 0.978723 (4850 1150);
PAINT WHITE (4850 1150);
DISPLAY INVISIBLE (4850 1150);
FORCEPROP 1 LAST PART_NUMBER CS21002FB06
J 0
(4840 850);
DISPLAY 0.638298 (4840 850);
DISPLAY INVISIBLE (4840 850);
FORCEADD Q_RES..2
(4800 1500);
FORCEPROP 1 LAST LOCATION R3280
J 0
(4845 1625);
DISPLAY 0.638298 (4845 1625);
FORCEPROP 0 LAST $SEC 1
J 0
(4850 1675);
DISPLAY 0.680851 (4850 1675);
PAINT MONO (4850 1675);
DISPLAY INVISIBLE (4850 1675);
FORCEPROP 0 LAST CDS_SEC 1
J 0
(4850 1675);
DISPLAY 1.021277 (4850 1675);
DISPLAY INVISIBLE (4850 1675);
FORCEPROP 1 LASTPIN (4800 1600) $PN 1
J 0
(4805 1562);
DISPLAY 0.787234 (4805 1562);
PAINT MONO (4805 1562);
FORCEPROP 1 LASTPIN (4800 1400) $PN 2
J 0
(4805 1410);
DISPLAY 0.787234 (4805 1410);
PAINT MONO (4805 1410);
FORCEPROP 1 LAST WATTAGE 1/16W
J 0
(4840 1475);
DISPLAY 0.638298 (4840 1475);
FORCEPROP 1 LAST MATERIAL EMPTY
J 0
(4840 1425);
DISPLAY 0.638298 (4840 1425);
PAINT RED (4840 1425);
FORCEPROP 1 LAST VALUE 1K
J 0
(4845 1575);
DISPLAY 0.638298 (4845 1575);
FORCEPROP 2 LAST ROOM PCIE REDRIVER BOM1
J 0
(4850 1675);
DISPLAY 0.446809 (4850 1675);
PAINT RED (4850 1675);
FORCEPROP 1 LAST PACK_TYPE 0402LF
J 0
(4840 1325);
DISPLAY 0.638298 (4840 1325);
FORCEPROP 1 LAST TOLERANCE 1%
J 0
(4845 1525);
DISPLAY 0.638298 (4845 1525);
FORCEPROP 2 LAST CDS_LIB pure_quanta
J 0
(4800 1500);
DISPLAY INVISIBLE (4800 1500);
FORCEPROP 1 LAST PATH I26
J 0
(4850 1675);
DISPLAY 0.978723 (4850 1675);
PAINT WHITE (4850 1675);
DISPLAY INVISIBLE (4850 1675);
FORCEPROP 1 LAST PART_NUMBER CS21002FB06
J 0
(4840 1375);
DISPLAY 0.638298 (4840 1375);
DISPLAY INVISIBLE (4840 1375);
FORCEADD UNIVERSAL_POWER..1
(4800 1800);
FORCEPROP 3 LASTPIN (4800 1750) SIG_NAME P3V3_AUX\g
J 0
(4810 1760);
DISPLAY 0.659574 (4810 1760);
PAINT MONO (4810 1760);
DISPLAY INVISIBLE (4810 1760);
FORCEPROP 1 LAST HDL_POWER P3V3_AUX
J 1
(4800 1850);
DISPLAY 0.872340 (4800 1850);
PAINT GREEN (4800 1850);
FORCEPROP 2 LAST CDS_LIB pure_quanta_power
J 0
(4800 1800);
DISPLAY INVISIBLE (4800 1800);
FORCEPROP 1 LAST PATH I27
J 0
(4850 1825);
DISPLAY 0.872340 (4850 1825);
PAINT AQUA (4850 1825);
DISPLAY INVISIBLE (4850 1825);
FORCEADD UNIVERSAL_GND..1
(3250 2375);
FORCEPROP 3 LASTPIN (3250 2425) SIG_NAME GND\g
J 0
(3260 2435);
DISPLAY 0.659574 (3260 2435);
PAINT MONO (3260 2435);
DISPLAY INVISIBLE (3260 2435);
FORCEPROP 2 LAST ROOM IO_SLOT
J 1
(3125 2400);
DISPLAY 0.744681 (3125 2400);
FORCEPROP 2 LAST CDS_LIB pure_quanta_power
J 0
(3250 2375);
DISPLAY INVISIBLE (3250 2375);
FORCEPROP 1 LAST HDL_POWER GND
J 1
(3275 2300);
DISPLAY 0.872340 (3275 2300);
PAINT GREEN (3275 2300);
DISPLAY INVISIBLE (3275 2300);
FORCEPROP 1 LAST PATH I28
J 0
(3325 2375);
DISPLAY 0.872340 (3325 2375);
PAINT AQUA (3325 2375);
DISPLAY INVISIBLE (3325 2375);
FORCEADD Q_RES..2
(3250 2675);
FORCEPROP 1 LAST LOCATION R3276
J 0
(3295 2800);
DISPLAY 0.978723 (3295 2800);
FORCEPROP 0 LAST $SEC 1
J 0
(3300 2850);
DISPLAY 0.680851 (3300 2850);
PAINT MONO (3300 2850);
DISPLAY INVISIBLE (3300 2850);
FORCEPROP 0 LAST CDS_SEC 1
J 0
(3300 2850);
DISPLAY 1.021277 (3300 2850);
DISPLAY INVISIBLE (3300 2850);
FORCEPROP 1 LASTPIN (3250 2775) $PN 1
J 0
(3255 2737);
DISPLAY 0.787234 (3255 2737);
PAINT MONO (3255 2737);
FORCEPROP 1 LASTPIN (3250 2575) $PN 2
J 0
(3255 2585);
DISPLAY 0.787234 (3255 2585);
PAINT MONO (3255 2585);
FORCEPROP 2 LAST ROOM PCIE REDRIVER BOM1
J 0
(3300 2850);
DISPLAY 0.446809 (3300 2850);
PAINT RED (3300 2850);
FORCEPROP 1 LAST MATERIAL EMPTY
J 0
(3290 2600);
DISPLAY 0.638298 (3290 2600);
PAINT RED (3290 2600);
FORCEPROP 1 LAST WATTAGE 1/16W
J 0
(3290 2650);
DISPLAY 0.638298 (3290 2650);
FORCEPROP 1 LAST VALUE 1K
J 0
(3295 2750);
DISPLAY 0.638298 (3295 2750);
FORCEPROP 1 LAST TOLERANCE 1%
J 0
(3295 2700);
DISPLAY 0.638298 (3295 2700);
FORCEPROP 1 LAST PACK_TYPE 0402LF
J 0
(3290 2500);
DISPLAY 0.638298 (3290 2500);
FORCEPROP 2 LAST CDS_LIB pure_quanta
J 0
(3250 2675);
DISPLAY INVISIBLE (3250 2675);
FORCEPROP 1 LAST PATH I29
J 0
(3300 2850);
DISPLAY 0.978723 (3300 2850);
PAINT WHITE (3300 2850);
DISPLAY INVISIBLE (3300 2850);
FORCEPROP 1 LAST PART_NUMBER CS21002FB06
J 0
(3290 2550);
DISPLAY 0.638298 (3290 2550);
DISPLAY INVISIBLE (3290 2550);
FORCEADD UNIVERSAL_GND..1
(2550 650);
FORCEPROP 3 LASTPIN (2550 700) SIG_NAME GND\g
J 0
(2560 710);
DISPLAY 0.659574 (2560 710);
PAINT MONO (2560 710);
DISPLAY INVISIBLE (2560 710);
FORCEPROP 2 LAST ROOM IO_SLOT
J 1
(2325 725);
DISPLAY 0.744681 (2325 725);
FORCEPROP 2 LAST CDS_LIB pure_quanta_power
J 0
(2550 650);
DISPLAY INVISIBLE (2550 650);
FORCEPROP 1 LAST HDL_POWER GND
J 1
(2575 575);
DISPLAY 0.872340 (2575 575);
PAINT GREEN (2575 575);
DISPLAY INVISIBLE (2575 575);
FORCEPROP 1 LAST PATH I3
J 0
(2625 650);
DISPLAY 0.872340 (2625 650);
PAINT AQUA (2625 650);
DISPLAY INVISIBLE (2625 650);
FORCEADD OFFPAGE..2
(3700 3000);
FORCEPROP 2 LAST $XR0 111 
J 0
(3889 3000);
DISPLAY 0.638298 (3889 3000);
PAINT MONO (3889 3000);
FORCEPROP 2 LAST CDS_LIB standard
J 0
(3700 3000);
DISPLAY INVISIBLE (3700 3000);
FORCEPROP 1 LAST OFFPAGE TRUE
J 0
(4025 2875);
DISPLAY 0.872340 (4025 2875);
PAINT GREEN (4025 2875);
DISPLAY INVISIBLE (4025 2875);
FORCEPROP 1 LAST COMMENT_BODY TRUE
J 0
(3655 2905);
DISPLAY 0.872340 (3655 2905);
PAINT GREEN (3655 2905);
DISPLAY INVISIBLE (3655 2905);
FORCEPROP 2 LAST PATH I30
J 0
(3900 3050);
DISPLAY 0.680851 (3900 3050);
DISPLAY INVISIBLE (3900 3050);
FORCEADD OFFPAGE..2
(3700 2950);
FORCEPROP 2 LAST $XR0 111 
J 0
(3889 2950);
DISPLAY 0.638298 (3889 2950);
PAINT MONO (3889 2950);
FORCEPROP 2 LAST CDS_LIB standard
J 0
(3700 2950);
DISPLAY INVISIBLE (3700 2950);
FORCEPROP 1 LAST OFFPAGE TRUE
J 0
(4025 2825);
DISPLAY 0.872340 (4025 2825);
PAINT GREEN (4025 2825);
DISPLAY INVISIBLE (4025 2825);
FORCEPROP 1 LAST COMMENT_BODY TRUE
J 0
(3655 2855);
DISPLAY 0.872340 (3655 2855);
PAINT GREEN (3655 2855);
DISPLAY INVISIBLE (3655 2855);
FORCEPROP 2 LAST PATH I31
J 0
(3900 3000);
DISPLAY 0.680851 (3900 3000);
DISPLAY INVISIBLE (3900 3000);
FORCEADD Q_RES..2
(3250 3250);
FORCEPROP 1 LAST LOCATION R3275
J 0
(3295 3375);
DISPLAY 0.978723 (3295 3375);
FORCEPROP 0 LAST $SEC 1
J 0
(3300 3425);
DISPLAY 0.680851 (3300 3425);
PAINT MONO (3300 3425);
DISPLAY INVISIBLE (3300 3425);
FORCEPROP 0 LAST CDS_SEC 1
J 0
(3300 3425);
DISPLAY 1.021277 (3300 3425);
DISPLAY INVISIBLE (3300 3425);
FORCEPROP 1 LASTPIN (3250 3350) $PN 1
J 0
(3255 3312);
DISPLAY 0.787234 (3255 3312);
PAINT MONO (3255 3312);
FORCEPROP 1 LASTPIN (3250 3150) $PN 2
J 0
(3255 3160);
DISPLAY 0.787234 (3255 3160);
PAINT MONO (3255 3160);
FORCEPROP 2 LAST ROOM PCIE REDRIVER BOM1
J 0
(3300 3425);
DISPLAY 0.680851 (3300 3425);
PAINT RED (3300 3425);
FORCEPROP 1 LAST VALUE 1K
J 0
(3295 3325);
DISPLAY 0.638298 (3295 3325);
FORCEPROP 1 LAST TOLERANCE 1%
J 0
(3295 3275);
DISPLAY 0.638298 (3295 3275);
FORCEPROP 1 LAST MATERIAL EMPTY
J 0
(3290 3175);
DISPLAY 0.638298 (3290 3175);
PAINT RED (3290 3175);
FORCEPROP 1 LAST WATTAGE 1/16W
J 0
(3290 3225);
DISPLAY 0.638298 (3290 3225);
FORCEPROP 1 LAST PACK_TYPE 0402LF
J 0
(3290 3075);
DISPLAY 0.638298 (3290 3075);
FORCEPROP 2 LAST CDS_LIB pure_quanta
J 0
(3250 3250);
DISPLAY INVISIBLE (3250 3250);
FORCEPROP 1 LAST PATH I32
J 0
(3300 3425);
DISPLAY 0.978723 (3300 3425);
PAINT WHITE (3300 3425);
DISPLAY INVISIBLE (3300 3425);
FORCEPROP 1 LAST PART_NUMBER CS21002FB06
J 0
(3290 3125);
DISPLAY 0.638298 (3290 3125);
DISPLAY INVISIBLE (3290 3125);
FORCEADD UNIVERSAL_GND..1
(5275 625);
FORCEPROP 3 LASTPIN (5275 675) SIG_NAME GND\g
J 0
(5285 685);
DISPLAY 0.659574 (5285 685);
PAINT MONO (5285 685);
DISPLAY INVISIBLE (5285 685);
FORCEPROP 2 LAST ROOM IO_SLOT
J 1
(5050 700);
DISPLAY 0.744681 (5050 700);
FORCEPROP 2 LAST CDS_LIB pure_quanta_power
J 0
(5275 625);
DISPLAY INVISIBLE (5275 625);
FORCEPROP 1 LAST HDL_POWER GND
J 1
(5300 550);
DISPLAY 0.872340 (5300 550);
PAINT GREEN (5300 550);
DISPLAY INVISIBLE (5300 550);
FORCEPROP 1 LAST PATH I33
J 0
(5350 625);
DISPLAY 0.872340 (5350 625);
PAINT AQUA (5350 625);
DISPLAY INVISIBLE (5350 625);
FORCEADD Q_RES..2
(5275 950);
FORCEPROP 1 LAST LOCATION R3282
J 0
(5320 1075);
DISPLAY 0.978723 (5320 1075);
FORCEPROP 0 LAST $SEC 1
J 0
(5325 1125);
DISPLAY 0.680851 (5325 1125);
PAINT MONO (5325 1125);
DISPLAY INVISIBLE (5325 1125);
FORCEPROP 0 LAST CDS_SEC 1
J 0
(5325 1125);
DISPLAY 1.021277 (5325 1125);
DISPLAY INVISIBLE (5325 1125);
FORCEPROP 1 LASTPIN (5275 1050) $PN 1
J 0
(5280 1012);
DISPLAY 0.787234 (5280 1012);
PAINT MONO (5280 1012);
FORCEPROP 1 LASTPIN (5275 850) $PN 2
J 0
(5280 860);
DISPLAY 0.787234 (5280 860);
PAINT MONO (5280 860);
FORCEPROP 2 LAST ROOM PCIE REDRIVER BOM1
J 0
(5325 1125);
DISPLAY 0.361702 (5325 1125);
PAINT RED (5325 1125);
FORCEPROP 1 LAST TOLERANCE 1%
J 0
(5320 975);
DISPLAY 0.638298 (5320 975);
FORCEPROP 1 LAST VALUE 68K
J 0
(5320 1025);
DISPLAY 0.638298 (5320 1025);
FORCEPROP 1 LAST PACK_TYPE 0402LF
J 0
(5315 775);
DISPLAY 0.638298 (5315 775);
FORCEPROP 1 LAST WATTAGE 1/16W
J 0
(5315 925);
DISPLAY 0.638298 (5315 925);
FORCEPROP 1 LAST MATERIAL EMPTY
J 0
(5315 875);
DISPLAY 0.638298 (5315 875);
PAINT RED (5315 875);
FORCEPROP 2 LAST CDS_LIB pure_quanta
J 0
(5275 950);
DISPLAY INVISIBLE (5275 950);
FORCEPROP 1 LAST PATH I34
J 0
(5325 1125);
DISPLAY 0.978723 (5325 1125);
PAINT WHITE (5325 1125);
DISPLAY INVISIBLE (5325 1125);
FORCEPROP 1 LAST PART_NUMBER CS36802FB04
J 0
(5315 825);
DISPLAY 0.638298 (5315 825);
DISPLAY INVISIBLE (5315 825);
FORCEADD UNIVERSAL_GND..1
(5675 625);
FORCEPROP 3 LASTPIN (5675 675) SIG_NAME GND\g
J 0
(5685 685);
DISPLAY 0.659574 (5685 685);
PAINT MONO (5685 685);
DISPLAY INVISIBLE (5685 685);
FORCEPROP 2 LAST ROOM IO_SLOT
J 1
(5450 700);
DISPLAY 0.744681 (5450 700);
FORCEPROP 2 LAST CDS_LIB pure_quanta_power
J 0
(5675 625);
DISPLAY INVISIBLE (5675 625);
FORCEPROP 1 LAST HDL_POWER GND
J 1
(5700 550);
DISPLAY 0.872340 (5700 550);
PAINT GREEN (5700 550);
DISPLAY INVISIBLE (5700 550);
FORCEPROP 1 LAST PATH I35
J 0
(5750 625);
DISPLAY 0.872340 (5750 625);
PAINT AQUA (5750 625);
DISPLAY INVISIBLE (5750 625);
FORCEADD Q_RES..2
(5675 925);
FORCEPROP 1 LAST LOCATION R3284
J 0
(5720 1050);
DISPLAY 0.978723 (5720 1050);
FORCEPROP 0 LAST $SEC 1
J 0
(5725 1100);
DISPLAY 0.680851 (5725 1100);
PAINT MONO (5725 1100);
DISPLAY INVISIBLE (5725 1100);
FORCEPROP 0 LAST CDS_SEC 1
J 0
(5725 1100);
DISPLAY 1.021277 (5725 1100);
DISPLAY INVISIBLE (5725 1100);
FORCEPROP 1 LASTPIN (5675 1025) $PN 1
J 0
(5680 987);
DISPLAY 0.787234 (5680 987);
PAINT MONO (5680 987);
FORCEPROP 1 LASTPIN (5675 825) $PN 2
J 0
(5680 835);
DISPLAY 0.787234 (5680 835);
PAINT MONO (5680 835);
FORCEPROP 2 LAST ROOM PCIE REDRIVER BOM1
J 0
(5725 1100);
DISPLAY 0.553191 (5725 1100);
PAINT RED (5725 1100);
FORCEPROP 1 LAST WATTAGE 1/16W
J 0
(5715 900);
DISPLAY 0.638298 (5715 900);
FORCEPROP 1 LAST MATERIAL CHIP
J 0
(5715 850);
DISPLAY 0.638298 (5715 850);
FORCEPROP 1 LAST TOLERANCE 1%
J 0
(5720 950);
DISPLAY 0.638298 (5720 950);
FORCEPROP 1 LAST VALUE 1K
J 0
(5720 1000);
DISPLAY 0.638298 (5720 1000);
FORCEPROP 1 LAST PACK_TYPE 0402LF
J 0
(5715 750);
DISPLAY 0.638298 (5715 750);
FORCEPROP 2 LAST CDS_LIB pure_quanta
J 0
(5675 925);
DISPLAY INVISIBLE (5675 925);
FORCEPROP 1 LAST PATH I36
J 0
(5725 1100);
DISPLAY 0.978723 (5725 1100);
PAINT WHITE (5725 1100);
DISPLAY INVISIBLE (5725 1100);
FORCEPROP 1 LAST PART_NUMBER CS21002FB06
J 0
(5715 800);
DISPLAY 0.638298 (5715 800);
DISPLAY INVISIBLE (5715 800);
FORCEADD Q_RES..2
(5675 1500);
FORCEPROP 1 LAST LOCATION R3283
J 0
(5720 1625);
DISPLAY 0.978723 (5720 1625);
FORCEPROP 0 LAST $SEC 1
J 0
(5725 1675);
DISPLAY 0.680851 (5725 1675);
PAINT MONO (5725 1675);
DISPLAY INVISIBLE (5725 1675);
FORCEPROP 0 LAST CDS_SEC 1
J 0
(5725 1675);
DISPLAY 1.021277 (5725 1675);
DISPLAY INVISIBLE (5725 1675);
FORCEPROP 1 LASTPIN (5675 1600) $PN 1
J 0
(5680 1562);
DISPLAY 0.787234 (5680 1562);
PAINT MONO (5680 1562);
FORCEPROP 1 LASTPIN (5675 1400) $PN 2
J 0
(5680 1410);
DISPLAY 0.787234 (5680 1410);
PAINT MONO (5680 1410);
FORCEPROP 2 LAST ROOM PCIE REDRIVER BOM1
J 0
(5725 1675);
DISPLAY 0.446809 (5725 1675);
PAINT RED (5725 1675);
FORCEPROP 1 LAST PACK_TYPE 0402LF
J 0
(5715 1325);
DISPLAY 0.638298 (5715 1325);
FORCEPROP 1 LAST TOLERANCE 1%
J 0
(5720 1525);
DISPLAY 0.638298 (5720 1525);
FORCEPROP 1 LAST VALUE 1K
J 0
(5720 1575);
DISPLAY 0.638298 (5720 1575);
FORCEPROP 1 LAST WATTAGE 1/16W
J 0
(5715 1475);
DISPLAY 0.638298 (5715 1475);
FORCEPROP 1 LAST MATERIAL EMPTY
J 0
(5715 1425);
DISPLAY 0.638298 (5715 1425);
PAINT RED (5715 1425);
FORCEPROP 2 LAST CDS_LIB pure_quanta
J 0
(5675 1500);
DISPLAY INVISIBLE (5675 1500);
FORCEPROP 1 LAST PATH I37
J 0
(5725 1675);
DISPLAY 0.978723 (5725 1675);
PAINT WHITE (5725 1675);
DISPLAY INVISIBLE (5725 1675);
FORCEPROP 1 LAST PART_NUMBER CS21002FB06
J 0
(5715 1375);
DISPLAY 0.638298 (5715 1375);
DISPLAY INVISIBLE (5715 1375);
FORCEADD OFFPAGE..2
(6175 1200);
FORCEPROP 2 LAST $XR0 111 
J 0
(6364 1200);
DISPLAY 0.638298 (6364 1200);
PAINT MONO (6364 1200);
FORCEPROP 2 LAST CDS_LIB standard
J 0
(6175 1200);
DISPLAY INVISIBLE (6175 1200);
FORCEPROP 1 LAST OFFPAGE TRUE
J 0
(6500 1075);
DISPLAY 0.872340 (6500 1075);
PAINT GREEN (6500 1075);
DISPLAY INVISIBLE (6500 1075);
FORCEPROP 1 LAST COMMENT_BODY TRUE
J 0
(6130 1105);
DISPLAY 0.872340 (6130 1105);
PAINT GREEN (6130 1105);
DISPLAY INVISIBLE (6130 1105);
FORCEPROP 2 LAST PATH I38
J 0
(6375 1250);
DISPLAY 0.680851 (6375 1250);
DISPLAY INVISIBLE (6375 1250);
FORCEADD OFFPAGE..2
(6175 1250);
FORCEPROP 2 LAST $XR0 111 
J 0
(6364 1250);
DISPLAY 0.638298 (6364 1250);
PAINT MONO (6364 1250);
FORCEPROP 2 LAST CDS_LIB standard
J 0
(6175 1250);
DISPLAY INVISIBLE (6175 1250);
FORCEPROP 1 LAST OFFPAGE TRUE
J 0
(6500 1125);
DISPLAY 0.872340 (6500 1125);
PAINT GREEN (6500 1125);
DISPLAY INVISIBLE (6500 1125);
FORCEPROP 1 LAST COMMENT_BODY TRUE
J 0
(6130 1155);
DISPLAY 0.872340 (6130 1155);
PAINT GREEN (6130 1155);
DISPLAY INVISIBLE (6130 1155);
FORCEPROP 2 LAST PATH I39
J 0
(6375 1300);
DISPLAY 0.680851 (6375 1300);
DISPLAY INVISIBLE (6375 1300);
FORCEADD Q_RES..2
(2550 1000);
FORCEPROP 1 LAST LOCATION R3272
J 0
(2595 1125);
DISPLAY 0.978723 (2595 1125);
FORCEPROP 0 LAST $SEC 1
J 0
(2600 1175);
DISPLAY 0.680851 (2600 1175);
PAINT MONO (2600 1175);
DISPLAY INVISIBLE (2600 1175);
FORCEPROP 0 LAST CDS_SEC 1
J 0
(2600 1175);
DISPLAY 1.021277 (2600 1175);
DISPLAY INVISIBLE (2600 1175);
FORCEPROP 1 LASTPIN (2550 1100) $PN 1
J 0
(2555 1062);
DISPLAY 0.787234 (2555 1062);
PAINT MONO (2555 1062);
FORCEPROP 1 LASTPIN (2550 900) $PN 2
J 0
(2555 910);
DISPLAY 0.787234 (2555 910);
PAINT MONO (2555 910);
FORCEPROP 2 LAST ROOM PCIE REDRIVER BOM1
J 0
(2600 1175);
DISPLAY 0.446809 (2600 1175);
PAINT RED (2600 1175);
FORCEPROP 1 LAST VALUE 1K
J 0
(2595 1075);
DISPLAY 0.638298 (2595 1075);
FORCEPROP 1 LAST TOLERANCE 1%
J 0
(2595 1025);
DISPLAY 0.638298 (2595 1025);
FORCEPROP 1 LAST PACK_TYPE 0402LF
J 0
(2590 825);
DISPLAY 0.638298 (2590 825);
FORCEPROP 1 LAST WATTAGE 1/16W
J 0
(2590 975);
DISPLAY 0.638298 (2590 975);
FORCEPROP 1 LAST MATERIAL EMPTY
J 0
(2590 925);
DISPLAY 0.638298 (2590 925);
PAINT RED (2590 925);
FORCEPROP 2 LAST CDS_LIB pure_quanta
J 0
(2550 1000);
DISPLAY INVISIBLE (2550 1000);
FORCEPROP 1 LAST PATH I4
J 0
(2600 1175);
DISPLAY 0.978723 (2600 1175);
PAINT WHITE (2600 1175);
DISPLAY INVISIBLE (2600 1175);
FORCEPROP 1 LAST PART_NUMBER CS21002FB06
J 0
(2590 875);
DISPLAY 0.638298 (2590 875);
DISPLAY INVISIBLE (2590 875);
FORCEADD UNIVERSAL_GND..1
(5725 4150);
FORCEPROP 3 LASTPIN (5725 4200) SIG_NAME GND\g
J 0
(5735 4210);
DISPLAY 0.659574 (5735 4210);
PAINT MONO (5735 4210);
DISPLAY INVISIBLE (5735 4210);
FORCEPROP 2 LAST CDS_LIB pure_quanta_power
J 0
(5725 4150);
DISPLAY INVISIBLE (5725 4150);
FORCEPROP 1 LAST HDL_POWER GND
J 1
(5750 4075);
DISPLAY 0.872340 (5750 4075);
PAINT GREEN (5750 4075);
DISPLAY INVISIBLE (5750 4075);
FORCEPROP 1 LAST PATH I40
J 0
(5800 4150);
DISPLAY 0.872340 (5800 4150);
PAINT AQUA (5800 4150);
DISPLAY INVISIBLE (5800 4150);
FORCEADD UNIVERSAL_GND..1
(6450 2375);
FORCEPROP 3 LASTPIN (6450 2425) SIG_NAME GND\g
J 0
(6460 2435);
DISPLAY 0.659574 (6460 2435);
PAINT MONO (6460 2435);
DISPLAY INVISIBLE (6460 2435);
FORCEPROP 2 LAST ROOM IO_SLOT
J 1
(6225 2450);
DISPLAY 0.744681 (6225 2450);
FORCEPROP 2 LAST CDS_LIB pure_quanta_power
J 0
(6450 2375);
DISPLAY INVISIBLE (6450 2375);
FORCEPROP 1 LAST HDL_POWER GND
J 1
(6475 2300);
DISPLAY 0.872340 (6475 2300);
PAINT GREEN (6475 2300);
DISPLAY INVISIBLE (6475 2300);
FORCEPROP 1 LAST PATH I41
J 0
(6525 2375);
DISPLAY 0.872340 (6525 2375);
PAINT AQUA (6525 2375);
DISPLAY INVISIBLE (6525 2375);
FORCEADD Q_RES..2
(6450 2725);
FORCEPROP 1 LAST LOCATION R3285
J 0
(6495 2850);
DISPLAY 0.638298 (6495 2850);
FORCEPROP 0 LAST $SEC 1
J 0
(6500 2900);
DISPLAY 0.680851 (6500 2900);
PAINT MONO (6500 2900);
DISPLAY INVISIBLE (6500 2900);
FORCEPROP 0 LAST CDS_SEC 1
J 0
(6500 2900);
DISPLAY 1.021277 (6500 2900);
DISPLAY INVISIBLE (6500 2900);
FORCEPROP 1 LASTPIN (6450 2825) $PN 1
J 0
(6455 2787);
DISPLAY 0.787234 (6455 2787);
PAINT MONO (6455 2787);
FORCEPROP 1 LASTPIN (6450 2625) $PN 2
J 0
(6455 2635);
DISPLAY 0.787234 (6455 2635);
PAINT MONO (6455 2635);
FORCEPROP 1 LAST WATTAGE 1/16W
J 0
(6490 2700);
DISPLAY 0.638298 (6490 2700);
FORCEPROP 1 LAST MATERIAL EMPTY
J 0
(6490 2650);
DISPLAY 0.638298 (6490 2650);
PAINT RED (6490 2650);
FORCEPROP 1 LAST PACK_TYPE 0402LF
J 0
(6490 2550);
DISPLAY 0.638298 (6490 2550);
FORCEPROP 1 LAST TOLERANCE 1%
J 0
(6495 2750);
DISPLAY 0.638298 (6495 2750);
FORCEPROP 1 LAST VALUE 68K
J 0
(6495 2800);
DISPLAY 0.638298 (6495 2800);
FORCEPROP 2 LAST ROOM PCIE REDRIVER BOM1
J 0
(6500 2900);
DISPLAY 0.361702 (6500 2900);
PAINT RED (6500 2900);
FORCEPROP 2 LAST CDS_LIB pure_quanta
J 0
(6450 2725);
DISPLAY INVISIBLE (6450 2725);
FORCEPROP 1 LAST PATH I42
J 0
(6500 2900);
DISPLAY 0.978723 (6500 2900);
PAINT WHITE (6500 2900);
DISPLAY INVISIBLE (6500 2900);
FORCEPROP 1 LAST PART_NUMBER CS36802FB04
J 0
(6490 2600);
DISPLAY 0.638298 (6490 2600);
DISPLAY INVISIBLE (6490 2600);
FORCEADD UNIVERSAL_GND..1
(6825 2375);
FORCEPROP 3 LASTPIN (6825 2425) SIG_NAME GND\g
J 0
(6835 2435);
DISPLAY 0.659574 (6835 2435);
PAINT MONO (6835 2435);
DISPLAY INVISIBLE (6835 2435);
FORCEPROP 2 LAST ROOM IO_SLOT
J 1
(6600 2450);
DISPLAY 0.744681 (6600 2450);
FORCEPROP 2 LAST CDS_LIB pure_quanta_power
J 0
(6825 2375);
DISPLAY INVISIBLE (6825 2375);
FORCEPROP 1 LAST HDL_POWER GND
J 1
(6850 2300);
DISPLAY 0.872340 (6850 2300);
PAINT GREEN (6850 2300);
DISPLAY INVISIBLE (6850 2300);
FORCEPROP 1 LAST PATH I43
J 0
(6900 2375);
DISPLAY 0.872340 (6900 2375);
PAINT AQUA (6900 2375);
DISPLAY INVISIBLE (6900 2375);
FORCEADD Q_RES..2
(6825 2725);
FORCEPROP 1 LAST LOCATION R3287
J 0
(6870 2850);
DISPLAY 0.978723 (6870 2850);
FORCEPROP 0 LAST $SEC 1
J 0
(6875 2900);
DISPLAY 0.680851 (6875 2900);
PAINT MONO (6875 2900);
DISPLAY INVISIBLE (6875 2900);
FORCEPROP 0 LAST CDS_SEC 1
J 0
(6875 2900);
DISPLAY 1.021277 (6875 2900);
DISPLAY INVISIBLE (6875 2900);
FORCEPROP 1 LASTPIN (6825 2825) $PN 1
J 0
(6830 2787);
DISPLAY 0.787234 (6830 2787);
PAINT MONO (6830 2787);
FORCEPROP 1 LASTPIN (6825 2625) $PN 2
J 0
(6830 2635);
DISPLAY 0.787234 (6830 2635);
PAINT MONO (6830 2635);
FORCEPROP 2 LAST ROOM PCIE REDRIVER BOM1
J 0
(6875 2900);
DISPLAY 0.446809 (6875 2900);
PAINT RED (6875 2900);
FORCEPROP 1 LAST WATTAGE 1/16W
J 0
(6865 2700);
DISPLAY 0.638298 (6865 2700);
FORCEPROP 1 LAST PACK_TYPE 0402LF
J 0
(6865 2550);
DISPLAY 0.638298 (6865 2550);
FORCEPROP 1 LAST MATERIAL EMPTY
J 0
(6865 2650);
DISPLAY 0.638298 (6865 2650);
PAINT RED (6865 2650);
FORCEPROP 1 LAST TOLERANCE 1%
J 0
(6870 2750);
DISPLAY 0.638298 (6870 2750);
FORCEPROP 1 LAST VALUE 1K
J 0
(6870 2800);
DISPLAY 0.638298 (6870 2800);
FORCEPROP 2 LAST CDS_LIB pure_quanta
J 0
(6825 2725);
DISPLAY INVISIBLE (6825 2725);
FORCEPROP 1 LAST PATH I44
J 0
(6875 2900);
DISPLAY 0.978723 (6875 2900);
PAINT WHITE (6875 2900);
DISPLAY INVISIBLE (6875 2900);
FORCEPROP 1 LAST PART_NUMBER CS21002FB06
J 0
(6865 2600);
DISPLAY 0.638298 (6865 2600);
DISPLAY INVISIBLE (6865 2600);
FORCEADD Q_RES..2
(6825 3250);
FORCEPROP 1 LAST LOCATION R3286
J 0
(6870 3375);
DISPLAY 0.638298 (6870 3375);
FORCEPROP 0 LAST $SEC 1
J 0
(6875 3425);
DISPLAY 0.680851 (6875 3425);
PAINT MONO (6875 3425);
DISPLAY INVISIBLE (6875 3425);
FORCEPROP 0 LAST CDS_SEC 1
J 0
(6875 3425);
DISPLAY 1.021277 (6875 3425);
DISPLAY INVISIBLE (6875 3425);
FORCEPROP 1 LASTPIN (6825 3350) $PN 1
J 0
(6830 3312);
DISPLAY 0.787234 (6830 3312);
PAINT MONO (6830 3312);
FORCEPROP 1 LASTPIN (6825 3150) $PN 2
J 0
(6830 3160);
DISPLAY 0.787234 (6830 3160);
PAINT MONO (6830 3160);
FORCEPROP 1 LAST MATERIAL EMPTY
J 0
(6865 3175);
DISPLAY 0.638298 (6865 3175);
PAINT RED (6865 3175);
FORCEPROP 2 LAST ROOM PCIE REDRIVER BOM1
J 0
(6875 3425);
DISPLAY 0.446809 (6875 3425);
PAINT RED (6875 3425);
FORCEPROP 1 LAST TOLERANCE 1%
J 0
(6870 3275);
DISPLAY 0.638298 (6870 3275);
FORCEPROP 1 LAST VALUE 1K
J 0
(6870 3325);
DISPLAY 0.638298 (6870 3325);
FORCEPROP 1 LAST WATTAGE 1/16W
J 0
(6865 3225);
DISPLAY 0.638298 (6865 3225);
FORCEPROP 1 LAST PACK_TYPE 0402LF
J 0
(6865 3075);
DISPLAY 0.638298 (6865 3075);
FORCEPROP 2 LAST CDS_LIB pure_quanta
J 0
(6825 3250);
DISPLAY INVISIBLE (6825 3250);
FORCEPROP 1 LAST PATH I45
J 0
(6875 3425);
DISPLAY 0.978723 (6875 3425);
PAINT WHITE (6875 3425);
DISPLAY INVISIBLE (6875 3425);
FORCEPROP 1 LAST PART_NUMBER CS21002FB06
J 0
(6865 3125);
DISPLAY 0.638298 (6865 3125);
DISPLAY INVISIBLE (6865 3125);
FORCEADD UNIVERSAL_POWER..1
(6825 3550);
FORCEPROP 3 LASTPIN (6825 3500) SIG_NAME P3V3_AUX\g
J 0
(6835 3510);
DISPLAY 0.659574 (6835 3510);
PAINT MONO (6835 3510);
DISPLAY INVISIBLE (6835 3510);
FORCEPROP 1 LAST HDL_POWER P3V3_AUX
J 1
(6825 3600);
DISPLAY 0.872340 (6825 3600);
PAINT GREEN (6825 3600);
FORCEPROP 2 LAST CDS_LIB pure_quanta_power
J 0
(6825 3550);
DISPLAY INVISIBLE (6825 3550);
FORCEPROP 1 LAST PATH I46
J 0
(6875 3575);
DISPLAY 0.872340 (6875 3575);
PAINT AQUA (6875 3575);
DISPLAY INVISIBLE (6875 3575);
FORCEADD OFFPAGE..4
R 2
(3500 4575);
FORCEPROP 2 LAST $XR0 113 
J 0
(3248 4575);
DISPLAY 0.638298 (3248 4575);
PAINT MONO (3248 4575);
FORCEPROP 2 LAST CDS_LIB standard
J 2
(3500 4575);
DISPLAY INVISIBLE (3500 4575);
FORCEPROP 1 LAST OFFPAGE TRUE
J 2
(3175 4450);
DISPLAY 0.872340 (3175 4450);
PAINT GREEN (3175 4450);
DISPLAY INVISIBLE (3175 4450);
FORCEPROP 1 LAST COMMENT_BODY TRUE
J 2
(3525 4475);
DISPLAY 0.872340 (3525 4475);
PAINT GREEN (3525 4475);
DISPLAY INVISIBLE (3525 4475);
FORCEPROP 2 LAST PATH I47
J 0
(3250 4625);
DISPLAY 0.680851 (3250 4625);
DISPLAY INVISIBLE (3250 4625);
FORCEADD OFFPAGE..4
R 2
(3500 4625);
FORCEPROP 2 LAST $XR0 113 
J 0
(3248 4625);
DISPLAY 0.638298 (3248 4625);
PAINT MONO (3248 4625);
FORCEPROP 2 LAST CDS_LIB standard
J 0
(3500 4625);
DISPLAY INVISIBLE (3500 4625);
FORCEPROP 1 LAST OFFPAGE TRUE
J 2
(3175 4500);
DISPLAY 0.872340 (3175 4500);
PAINT GREEN (3175 4500);
DISPLAY INVISIBLE (3175 4500);
FORCEPROP 1 LAST COMMENT_BODY TRUE
J 2
(3525 4525);
DISPLAY 0.872340 (3525 4525);
PAINT GREEN (3525 4525);
DISPLAY INVISIBLE (3525 4525);
FORCEPROP 2 LAST PATH I48
J 0
(3250 4675);
DISPLAY 0.680851 (3250 4675);
DISPLAY INVISIBLE (3250 4675);
FORCEADD OFFPAGE..4
R 2
(3500 4725);
FORCEPROP 2 LAST $XR0 113 
J 0
(3248 4725);
DISPLAY 0.638298 (3248 4725);
PAINT MONO (3248 4725);
FORCEPROP 2 LAST CDS_LIB standard
J 0
(3500 4725);
DISPLAY INVISIBLE (3500 4725);
FORCEPROP 1 LAST OFFPAGE TRUE
J 2
(3175 4600);
DISPLAY 0.872340 (3175 4600);
PAINT GREEN (3175 4600);
DISPLAY INVISIBLE (3175 4600);
FORCEPROP 1 LAST COMMENT_BODY TRUE
J 2
(3525 4625);
DISPLAY 0.872340 (3525 4625);
PAINT GREEN (3525 4625);
DISPLAY INVISIBLE (3525 4625);
FORCEPROP 2 LAST PATH I49
J 0
(3250 4775);
DISPLAY 0.680851 (3250 4775);
DISPLAY INVISIBLE (3250 4775);
FORCEADD Q_RES..2
(2550 1525);
FORCEPROP 1 LAST LOCATION R3271
J 0
(2600 1625);
DISPLAY 0.638298 (2600 1625);
FORCEPROP 0 LAST $SEC 1
J 0
(2600 1700);
DISPLAY 0.680851 (2600 1700);
PAINT MONO (2600 1700);
DISPLAY INVISIBLE (2600 1700);
FORCEPROP 0 LAST CDS_SEC 1
J 0
(2600 1700);
DISPLAY 1.021277 (2600 1700);
DISPLAY INVISIBLE (2600 1700);
FORCEPROP 1 LASTPIN (2550 1625) $PN 1
J 0
(2555 1587);
DISPLAY 0.787234 (2555 1587);
PAINT MONO (2555 1587);
FORCEPROP 1 LASTPIN (2550 1425) $PN 2
J 0
(2555 1435);
DISPLAY 0.787234 (2555 1435);
PAINT MONO (2555 1435);
FORCEPROP 1 LAST MATERIAL EMPTY
J 0
(2590 1450);
DISPLAY 0.638298 (2590 1450);
PAINT RED (2590 1450);
FORCEPROP 1 LAST WATTAGE 1/16W
J 0
(2590 1500);
DISPLAY 0.638298 (2590 1500);
FORCEPROP 1 LAST TOLERANCE 1%
J 0
(2595 1550);
DISPLAY 0.638298 (2595 1550);
FORCEPROP 1 LAST VALUE 1K
J 0
(2595 1600);
DISPLAY 0.638298 (2595 1600);
FORCEPROP 1 LAST PACK_TYPE 0402LF
J 0
(2590 1350);
DISPLAY 0.638298 (2590 1350);
FORCEPROP 2 LAST ROOM PCIE REDRIVER BOM1
J 0
(2600 1675);
DISPLAY 0.553191 (2600 1675);
PAINT RED (2600 1675);
FORCEPROP 2 LAST CDS_LIB pure_quanta
J 0
(2550 1525);
DISPLAY INVISIBLE (2550 1525);
FORCEPROP 1 LAST PATH I5
J 0
(2600 1700);
DISPLAY 0.978723 (2600 1700);
PAINT WHITE (2600 1700);
DISPLAY INVISIBLE (2600 1700);
FORCEPROP 1 LAST PART_NUMBER CS21002FB06
J 0
(2590 1400);
DISPLAY 0.638298 (2590 1400);
DISPLAY INVISIBLE (2590 1400);
FORCEADD OFFPAGE..4
R 2
(3500 4875);
FORCEPROP 2 LAST $XR0 111 
J 0
(3248 4875);
DISPLAY 0.638298 (3248 4875);
PAINT MONO (3248 4875);
FORCEPROP 2 LAST CDS_LIB standard
J 0
(3500 4875);
DISPLAY INVISIBLE (3500 4875);
FORCEPROP 1 LAST OFFPAGE TRUE
J 2
(3175 4750);
DISPLAY 0.872340 (3175 4750);
PAINT GREEN (3175 4750);
DISPLAY INVISIBLE (3175 4750);
FORCEPROP 1 LAST COMMENT_BODY TRUE
J 2
(3525 4775);
DISPLAY 0.872340 (3525 4775);
PAINT GREEN (3525 4775);
DISPLAY INVISIBLE (3525 4775);
FORCEPROP 2 LAST PATH I50
J 0
(3250 4925);
DISPLAY 0.680851 (3250 4925);
DISPLAY INVISIBLE (3250 4925);
FORCEADD OFFPAGE..4
R 2
(3500 4775);
FORCEPROP 2 LAST $XR0 113 
J 0
(3248 4775);
DISPLAY 0.638298 (3248 4775);
PAINT MONO (3248 4775);
FORCEPROP 2 LAST CDS_LIB standard
J 0
(3500 4775);
DISPLAY INVISIBLE (3500 4775);
FORCEPROP 1 LAST OFFPAGE TRUE
J 2
(3175 4650);
DISPLAY 0.872340 (3175 4650);
PAINT GREEN (3175 4650);
DISPLAY INVISIBLE (3175 4650);
FORCEPROP 1 LAST COMMENT_BODY TRUE
J 2
(3525 4675);
DISPLAY 0.872340 (3525 4675);
PAINT GREEN (3525 4675);
DISPLAY INVISIBLE (3525 4675);
FORCEPROP 2 LAST PATH I51
J 0
(3250 4825);
DISPLAY 0.680851 (3250 4825);
DISPLAY INVISIBLE (3250 4825);
FORCEADD OFFPAGE..4
R 2
(3500 4925);
FORCEPROP 2 LAST $XR0 111 
J 0
(3248 4925);
DISPLAY 0.638298 (3248 4925);
PAINT MONO (3248 4925);
FORCEPROP 2 LAST CDS_LIB standard
J 0
(3500 4925);
DISPLAY INVISIBLE (3500 4925);
FORCEPROP 1 LAST OFFPAGE TRUE
J 2
(3175 4800);
DISPLAY 0.872340 (3175 4800);
PAINT GREEN (3175 4800);
DISPLAY INVISIBLE (3175 4800);
FORCEPROP 1 LAST COMMENT_BODY TRUE
J 2
(3525 4825);
DISPLAY 0.872340 (3525 4825);
PAINT GREEN (3525 4825);
DISPLAY INVISIBLE (3525 4825);
FORCEPROP 2 LAST PATH I52
J 0
(3250 4975);
DISPLAY 0.680851 (3250 4975);
DISPLAY INVISIBLE (3250 4975);
FORCEADD OFFPAGE..4
R 2
(3500 5075);
FORCEPROP 2 LAST $XR0 111 
J 0
(3248 5075);
DISPLAY 0.638298 (3248 5075);
PAINT MONO (3248 5075);
FORCEPROP 2 LAST CDS_LIB standard
J 0
(3500 5075);
DISPLAY INVISIBLE (3500 5075);
FORCEPROP 1 LAST OFFPAGE TRUE
J 2
(3175 4950);
DISPLAY 0.872340 (3175 4950);
PAINT GREEN (3175 4950);
DISPLAY INVISIBLE (3175 4950);
FORCEPROP 1 LAST COMMENT_BODY TRUE
J 2
(3525 4975);
DISPLAY 0.872340 (3525 4975);
PAINT GREEN (3525 4975);
DISPLAY INVISIBLE (3525 4975);
FORCEPROP 2 LAST PATH I53
J 0
(3250 5125);
DISPLAY 0.680851 (3250 5125);
DISPLAY INVISIBLE (3250 5125);
FORCEADD OFFPAGE..4
R 2
(3500 5025);
FORCEPROP 2 LAST $XR0 111 
J 0
(3248 5025);
DISPLAY 0.638298 (3248 5025);
PAINT MONO (3248 5025);
FORCEPROP 2 LAST CDS_LIB standard
J 0
(3500 5025);
DISPLAY INVISIBLE (3500 5025);
FORCEPROP 1 LAST OFFPAGE TRUE
J 2
(3175 4900);
DISPLAY 0.872340 (3175 4900);
PAINT GREEN (3175 4900);
DISPLAY INVISIBLE (3175 4900);
FORCEPROP 1 LAST COMMENT_BODY TRUE
J 2
(3525 4925);
DISPLAY 0.872340 (3525 4925);
PAINT GREEN (3525 4925);
DISPLAY INVISIBLE (3525 4925);
FORCEPROP 2 LAST PATH I54
J 0
(3250 5075);
DISPLAY 0.680851 (3250 5075);
DISPLAY INVISIBLE (3250 5075);
FORCEADD OFFPAGE..4
R 2
(3500 5175);
FORCEPROP 2 LAST $XR0 111 
J 0
(3248 5175);
DISPLAY 0.638298 (3248 5175);
PAINT MONO (3248 5175);
FORCEPROP 2 LAST CDS_LIB standard
J 0
(3500 5175);
DISPLAY INVISIBLE (3500 5175);
FORCEPROP 1 LAST OFFPAGE TRUE
J 2
(3175 5050);
DISPLAY 0.872340 (3175 5050);
PAINT GREEN (3175 5050);
DISPLAY INVISIBLE (3175 5050);
FORCEPROP 1 LAST COMMENT_BODY TRUE
J 2
(3525 5075);
DISPLAY 0.872340 (3525 5075);
PAINT GREEN (3525 5075);
DISPLAY INVISIBLE (3525 5075);
FORCEPROP 2 LAST PATH I55
J 0
(3250 5225);
DISPLAY 0.680851 (3250 5225);
DISPLAY INVISIBLE (3250 5225);
FORCEADD OFFPAGE..4
R 2
(3500 5375);
FORCEPROP 2 LAST $XR0 111 
J 0
(3248 5375);
DISPLAY 0.638298 (3248 5375);
PAINT MONO (3248 5375);
FORCEPROP 2 LAST CDS_LIB standard
J 0
(3500 5375);
DISPLAY INVISIBLE (3500 5375);
FORCEPROP 1 LAST OFFPAGE TRUE
J 2
(3175 5250);
DISPLAY 0.872340 (3175 5250);
PAINT GREEN (3175 5250);
DISPLAY INVISIBLE (3175 5250);
FORCEPROP 1 LAST COMMENT_BODY TRUE
J 2
(3525 5275);
DISPLAY 0.872340 (3525 5275);
PAINT GREEN (3525 5275);
DISPLAY INVISIBLE (3525 5275);
FORCEPROP 2 LAST PATH I56
J 0
(3250 5425);
DISPLAY 0.680851 (3250 5425);
DISPLAY INVISIBLE (3250 5425);
FORCEADD OFFPAGE..4
R 2
(3500 5225);
FORCEPROP 2 LAST $XR0 111 
J 0
(3248 5225);
DISPLAY 0.638298 (3248 5225);
PAINT MONO (3248 5225);
FORCEPROP 2 LAST CDS_LIB standard
J 0
(3500 5225);
DISPLAY INVISIBLE (3500 5225);
FORCEPROP 1 LAST OFFPAGE TRUE
J 2
(3175 5100);
DISPLAY 0.872340 (3175 5100);
PAINT GREEN (3175 5100);
DISPLAY INVISIBLE (3175 5100);
FORCEPROP 1 LAST COMMENT_BODY TRUE
J 2
(3525 5125);
DISPLAY 0.872340 (3525 5125);
PAINT GREEN (3525 5125);
DISPLAY INVISIBLE (3525 5125);
FORCEPROP 2 LAST PATH I57
J 0
(3250 5275);
DISPLAY 0.680851 (3250 5275);
DISPLAY INVISIBLE (3250 5275);
FORCEADD OFFPAGE..4
R 2
(3500 5425);
FORCEPROP 2 LAST $XR0 111 
J 0
(3248 5425);
DISPLAY 0.638298 (3248 5425);
PAINT MONO (3248 5425);
FORCEPROP 2 LAST CDS_LIB standard
J 0
(3500 5425);
DISPLAY INVISIBLE (3500 5425);
FORCEPROP 1 LAST OFFPAGE TRUE
J 2
(3175 5300);
DISPLAY 0.872340 (3175 5300);
PAINT GREEN (3175 5300);
DISPLAY INVISIBLE (3175 5300);
FORCEPROP 1 LAST COMMENT_BODY TRUE
J 2
(3525 5325);
DISPLAY 0.872340 (3525 5325);
PAINT GREEN (3525 5325);
DISPLAY INVISIBLE (3525 5325);
FORCEPROP 2 LAST PATH I58
J 0
(3250 5475);
DISPLAY 0.680851 (3250 5475);
DISPLAY INVISIBLE (3250 5475);
FORCEADD UNIVERSAL_GND..1
(2700 5550);
FORCEPROP 3 LASTPIN (2700 5600) SIG_NAME GND\g
J 0
(2710 5610);
DISPLAY 0.659574 (2710 5610);
PAINT MONO (2710 5610);
DISPLAY INVISIBLE (2710 5610);
FORCEPROP 2 LAST CDS_LIB pure_quanta_power
J 0
(2700 5550);
DISPLAY INVISIBLE (2700 5550);
FORCEPROP 1 LAST HDL_POWER GND
J 1
(2725 5475);
DISPLAY 0.872340 (2725 5475);
PAINT GREEN (2725 5475);
DISPLAY INVISIBLE (2725 5475);
FORCEPROP 1 LAST PATH I59
J 0
(2775 5550);
DISPLAY 0.872340 (2775 5550);
PAINT AQUA (2775 5550);
DISPLAY INVISIBLE (2775 5550);
FORCEADD UNIVERSAL_POWER..1
(2550 1825);
FORCEPROP 3 LASTPIN (2550 1775) SIG_NAME P3V3_AUX\g
J 0
(2560 1785);
DISPLAY 0.659574 (2560 1785);
PAINT MONO (2560 1785);
DISPLAY INVISIBLE (2560 1785);
FORCEPROP 1 LAST HDL_POWER P3V3_AUX
J 1
(2550 1875);
DISPLAY 0.872340 (2550 1875);
PAINT GREEN (2550 1875);
FORCEPROP 2 LAST CDS_LIB pure_quanta_power
J 0
(2550 1825);
DISPLAY INVISIBLE (2550 1825);
FORCEPROP 1 LAST PATH I6
J 0
(2600 1850);
DISPLAY 0.872340 (2600 1850);
PAINT AQUA (2600 1850);
DISPLAY INVISIBLE (2600 1850);
FORCEADD Q_CAP..1
(2275 5875);
FORCEPROP 1 LAST LOCATION C1867
J 0
(2325 5975);
DISPLAY 0.978723 (2325 5975);
FORCEPROP 0 LAST $SEC 1
J 0
(2325 6025);
DISPLAY 0.680851 (2325 6025);
PAINT MONO (2325 6025);
DISPLAY INVISIBLE (2325 6025);
FORCEPROP 0 LAST CDS_SEC 1
J 0
(2325 6025);
DISPLAY 1.021277 (2325 6025);
DISPLAY INVISIBLE (2325 6025);
FORCEPROP 1 LASTPIN (2275 5975) $PN 1
J 0
(2285 5955);
DISPLAY 0.787234 (2285 5955);
PAINT MONO (2285 5955);
FORCEPROP 1 LASTPIN (2275 5775) $PN 2
J 0
(2285 5755);
DISPLAY 0.787234 (2285 5755);
PAINT MONO (2285 5755);
FORCEPROP 1 LAST TOLERANCE 10%
J 0
(2325 5825);
DISPLAY 0.638298 (2325 5825);
FORCEPROP 1 LAST MATERIAL X6S
J 0
(2325 5775);
DISPLAY 0.638298 (2325 5775);
FORCEPROP 1 LAST VOLTAGE 25V
J 0
(2325 5875);
DISPLAY 0.638298 (2325 5875);
FORCEPROP 1 LAST VALUE 10UF
J 0
(2325 5925);
DISPLAY 0.638298 (2325 5925);
FORCEPROP 1 LAST PACK_TYPE C0805
J 0
(2325 5675);
DISPLAY 0.638298 (2325 5675);
FORCEPROP 2 LAST ROOM PCIE REDRIVER BOM1
J 0
(2325 6025);
DISPLAY 0.553191 (2325 6025);
PAINT RED (2325 6025);
FORCEPROP 2 LAST CDS_LIB pure_quanta
J 0
(2275 5875);
DISPLAY INVISIBLE (2275 5875);
FORCEPROP 1 LAST PATH I60
J 0
(2325 6025);
DISPLAY 0.978723 (2325 6025);
PAINT WHITE (2325 6025);
DISPLAY INVISIBLE (2325 6025);
FORCEPROP 1 LAST PART_NUMBER CH6104KEA00
J 0
(2325 5725);
DISPLAY 0.638298 (2325 5725);
DISPLAY INVISIBLE (2325 5725);
FORCEADD Q_CAP..1
(2825 5875);
FORCEPROP 1 LAST LOCATION C1863
J 0
(2875 5975);
DISPLAY 0.787234 (2875 5975);
FORCEPROP 2 LAST $SEC 1
J 0
(2875 6075);
DISPLAY 0.680851 (2875 6075);
PAINT MONO (2875 6075);
DISPLAY INVISIBLE (2875 6075);
FORCEPROP 2 LAST CDS_SEC 1
J 0
(2875 6075);
DISPLAY 1.021277 (2875 6075);
DISPLAY INVISIBLE (2875 6075);
FORCEPROP 1 LASTPIN (2825 5975) $PN 1
J 0
(2835 5955);
DISPLAY 0.787234 (2835 5955);
FORCEPROP 1 LASTPIN (2825 5775) $PN 2
J 0
(2835 5755);
DISPLAY 0.787234 (2835 5755);
FORCEPROP 1 LAST VALUE 0.1UF
J 0
(2875 5925);
DISPLAY 0.638298 (2875 5925);
FORCEPROP 1 LAST TOLERANCE 10%
J 0
(2875 5825);
DISPLAY 0.638298 (2875 5825);
FORCEPROP 1 LAST VOLTAGE 25V
J 0
(2875 5875);
DISPLAY 0.638298 (2875 5875);
FORCEPROP 1 LAST PACK_TYPE 0402
J 0
(2875 5725);
DISPLAY 0.638298 (2875 5725);
FORCEPROP 1 LAST MATERIAL X7R
J 0
(2875 5775);
DISPLAY 0.638298 (2875 5775);
FORCEPROP 2 LAST ROOM PCIE REDRIVER BOM1
J 0
(2850 6025);
DISPLAY 0.489362 (2850 6025);
PAINT RED (2850 6025);
FORCEPROP 2 LAST CDS_LIB pure_quanta
J 0
(2825 5875);
PAINT MONO (2825 5875);
DISPLAY INVISIBLE (2825 5875);
FORCEPROP 1 LAST PATH I61
J 0
(2875 6025);
DISPLAY 0.978723 (2875 6025);
PAINT WHITE (2875 6025);
DISPLAY INVISIBLE (2875 6025);
FORCEPROP 1 LAST PART_NUMBER CH4104K1B00
J 0
(2875 5725);
DISPLAY 0.808511 (2875 5725);
DISPLAY INVISIBLE (2875 5725);
FORCEADD Q_CAP..1
(3275 5875);
FORCEPROP 1 LAST LOCATION C1864
J 0
(3325 5975);
DISPLAY 0.787234 (3325 5975);
FORCEPROP 2 LAST $SEC 1
J 0
(3325 6075);
DISPLAY 0.680851 (3325 6075);
PAINT MONO (3325 6075);
DISPLAY INVISIBLE (3325 6075);
FORCEPROP 2 LAST CDS_SEC 1
J 0
(3325 6075);
DISPLAY 1.021277 (3325 6075);
DISPLAY INVISIBLE (3325 6075);
FORCEPROP 1 LASTPIN (3275 5975) $PN 1
J 0
(3285 5955);
DISPLAY 0.787234 (3285 5955);
FORCEPROP 1 LASTPIN (3275 5775) $PN 2
J 0
(3285 5755);
DISPLAY 0.787234 (3285 5755);
FORCEPROP 1 LAST TOLERANCE 10%
J 0
(3325 5825);
DISPLAY 0.638298 (3325 5825);
FORCEPROP 1 LAST PACK_TYPE 0402
J 0
(3325 5725);
DISPLAY 0.638298 (3325 5725);
FORCEPROP 1 LAST MATERIAL X7R
J 0
(3325 5775);
DISPLAY 0.638298 (3325 5775);
FORCEPROP 1 LAST VALUE 0.1UF
J 0
(3325 5925);
DISPLAY 0.638298 (3325 5925);
FORCEPROP 1 LAST VOLTAGE 25V
J 0
(3325 5875);
DISPLAY 0.638298 (3325 5875);
FORCEPROP 2 LAST ROOM PCIE REDRIVER BOM1
J 0
(3300 6025);
DISPLAY 0.489362 (3300 6025);
PAINT RED (3300 6025);
FORCEPROP 2 LAST CDS_LIB pure_quanta
J 0
(3275 5875);
PAINT MONO (3275 5875);
DISPLAY INVISIBLE (3275 5875);
FORCEPROP 1 LAST PATH I62
J 0
(3325 6025);
DISPLAY 0.978723 (3325 6025);
PAINT WHITE (3325 6025);
DISPLAY INVISIBLE (3325 6025);
FORCEPROP 1 LAST PART_NUMBER CH4104K1B00
J 0
(3325 5725);
DISPLAY 0.808511 (3325 5725);
DISPLAY INVISIBLE (3325 5725);
FORCEADD PI3EQX12902AZLEX..1
(5200 5050);
FORCEPROP 1 LAST LOCATION U237
J 0
(4905 6046);
DISPLAY 0.723404 (4905 6046);
PAINT GREEN (4905 6046);
FORCEPROP 0 LAST $SEC 1
J 0
(4925 6200);
DISPLAY 0.680851 (4925 6200);
PAINT MONO (4925 6200);
DISPLAY INVISIBLE (4925 6200);
FORCEPROP 0 LAST CDS_SEC 1
J 0
(4925 6200);
DISPLAY 1.021277 (4925 6200);
DISPLAY INVISIBLE (4925 6200);
FORCEPROP 0 LASTPIN (4750 4725) $PN 3
J 2
(4740 4735);
DISPLAY 0.680851 (4740 4735);
PAINT MONO (4740 4735);
FORCEPROP 0 LASTPIN (4750 4775) $PN 2
J 2
(4740 4785);
DISPLAY 0.680851 (4740 4785);
PAINT MONO (4740 4785);
FORCEPROP 0 LASTPIN (5650 5675) $PN 23
J 0
(5660 5685);
DISPLAY 0.680851 (5660 5685);
PAINT MONO (5660 5685);
FORCEPROP 0 LASTPIN (5650 5725) $PN 24
J 0
(5660 5735);
DISPLAY 0.680851 (5660 5735);
PAINT MONO (5660 5735);
FORCEPROP 0 LASTPIN (4750 4575) $PN 18
J 2
(4740 4585);
DISPLAY 0.680851 (4740 4585);
PAINT MONO (4740 4585);
FORCEPROP 0 LASTPIN (4750 4625) $PN 17
J 2
(4740 4635);
DISPLAY 0.680851 (4740 4635);
PAINT MONO (4740 4635);
FORCEPROP 0 LASTPIN (5650 5475) $PN 8
J 0
(5660 5485);
DISPLAY 0.680851 (5660 5485);
PAINT MONO (5660 5485);
FORCEPROP 0 LASTPIN (5650 5525) $PN 9
J 0
(5660 5535);
DISPLAY 0.680851 (5660 5535);
PAINT MONO (5660 5535);
FORCEPROP 0 LASTPIN (5650 5025) $PN 11
J 0
(5660 5035);
DISPLAY 0.680851 (5660 5035);
PAINT MONO (5660 5035);
FORCEPROP 0 LASTPIN (4750 5075) $PN 21
J 2
(4740 5085);
DISPLAY 0.680851 (4740 5085);
PAINT MONO (4740 5085);
FORCEPROP 0 LASTPIN (4750 5025) $PN 26
J 2
(4740 5035);
DISPLAY 0.680851 (4740 5035);
PAINT MONO (4740 5035);
FORCEPROP 0 LASTPIN (4750 4925) $PN 20
J 2
(4740 4935);
DISPLAY 0.680851 (4740 4935);
PAINT MONO (4740 4935);
FORCEPROP 0 LASTPIN (4750 4875) $PN 15
J 2
(4740 4885);
DISPLAY 0.680851 (4740 4885);
PAINT MONO (4740 4885);
FORCEPROP 0 LASTPIN (4750 5425) $PN 27
J 2
(4740 5435);
DISPLAY 0.680851 (4740 5435);
PAINT MONO (4740 5435);
FORCEPROP 0 LASTPIN (4750 5375) $PN 14
J 2
(4740 5385);
DISPLAY 0.680851 (4740 5385);
PAINT MONO (4740 5385);
FORCEPROP 0 LASTPIN (5650 4875) $PN 4
J 0
(5660 4885);
DISPLAY 0.680851 (5660 4885);
PAINT MONO (5660 4885);
FORCEPROP 0 LASTPIN (5650 4825) $PN 6
J 0
(5660 4835);
DISPLAY 0.680851 (5660 4835);
PAINT MONO (5660 4835);
FORCEPROP 0 LASTPIN (5650 4775) $PN 7
J 0
(5660 4785);
DISPLAY 0.680851 (5660 4785);
PAINT MONO (5660 4785);
FORCEPROP 0 LASTPIN (5650 4725) $PN 13
J 0
(5660 4735);
DISPLAY 0.680851 (5660 4735);
PAINT MONO (5660 4735);
FORCEPROP 0 LASTPIN (5650 4675) $PN 19
J 0
(5660 4685);
DISPLAY 0.680851 (5660 4685);
PAINT MONO (5660 4685);
FORCEPROP 0 LASTPIN (5650 4625) $PN 22
J 0
(5660 4635);
DISPLAY 0.680851 (5660 4635);
PAINT MONO (5660 4635);
FORCEPROP 0 LASTPIN (5650 4575) $PN 28
J 0
(5660 4585);
DISPLAY 0.680851 (5660 4585);
PAINT MONO (5660 4585);
FORCEPROP 0 LASTPIN (5650 4375) $PN TH
J 0
(5660 4385);
DISPLAY 0.680851 (5660 4385);
PAINT MONO (5660 4385);
FORCEPROP 0 LASTPIN (5650 5325) $PN 30
J 0
(5660 5335);
DISPLAY 0.680851 (5660 5335);
PAINT MONO (5660 5335);
FORCEPROP 0 LASTPIN (4750 5225) $PN 29
J 2
(4740 5235);
DISPLAY 0.680851 (4740 5235);
PAINT MONO (4740 5235);
FORCEPROP 0 LASTPIN (4750 5175) $PN 12
J 2
(4740 5185);
DISPLAY 0.680851 (4740 5185);
PAINT MONO (4740 5185);
FORCEPROP 0 LASTPIN (5650 5175) $PN 5
J 0
(5660 5185);
DISPLAY 0.680851 (5660 5185);
PAINT MONO (5660 5185);
FORCEPROP 0 LASTPIN (4750 5725) $PN 1
J 2
(4740 5735);
DISPLAY 0.680851 (4740 5735);
PAINT MONO (4740 5735);
FORCEPROP 0 LASTPIN (4750 5675) $PN 10
J 2
(4740 5685);
DISPLAY 0.680851 (4740 5685);
PAINT MONO (4740 5685);
FORCEPROP 0 LASTPIN (4750 5625) $PN 16
J 2
(4740 5635);
DISPLAY 0.680851 (4740 5635);
PAINT MONO (4740 5635);
FORCEPROP 0 LASTPIN (4750 5575) $PN 25
J 2
(4740 5585);
DISPLAY 0.680851 (4740 5585);
PAINT MONO (4740 5585);
FORCEPROP 1 LAST MATERIAL IC
J 0
(4905 5832);
DISPLAY 0.723404 (4905 5832);
PAINT GREEN (4905 5832);
FORCEPROP 2 LAST PART_TYPE SMLF
J 0
(4925 6150);
DISPLAY 1.021277 (4925 6150);
FORCEPROP 2 LAST VALUE PI3EQX12902AZLEX
J 0
(4925 6100);
DISPLAY 1.021277 (4925 6100);
FORCEPROP 2 LAST ROOM PCIE REDRIVER BOM1
J 0
(4925 6200);
DISPLAY 0.680851 (4925 6200);
PAINT RED (4925 6200);
FORCEPROP 1 LAST NEEDS_NO_SIZE TRUE
J 0
(5200 5050);
DISPLAY 0.723404 (5200 5050);
PAINT GREEN (5200 5050);
DISPLAY INVISIBLE (5200 5050);
FORCEPROP 1 LAST CDS_LMAN_SYM_OUTLINE -300,775,300,-775
J 0
(5200 5050);
DISPLAY 0.468085 (5200 5050);
PAINT GREEN (5200 5050);
DISPLAY INVISIBLE (5200 5050);
FORCEPROP 2 LAST CDS_LIB pure_quanta
J 0
(5200 5050);
DISPLAY INVISIBLE (5200 5050);
FORCEPROP 1 LAST PATH I63
J 0
(5200 5050);
DISPLAY 0.723404 (5200 5050);
PAINT GREEN (5200 5050);
DISPLAY INVISIBLE (5200 5050);
FORCEPROP 1 LAST PART_NUMBER AL012902001
J 0
(4905 5935);
DISPLAY 0.723404 (4905 5935);
PAINT GREEN (4905 5935);
DISPLAY INVISIBLE (4905 5935);
FORCEADD Q_CAP..1
(3750 5875);
FORCEPROP 1 LAST LOCATION C1865
J 0
(3800 5975);
DISPLAY 0.787234 (3800 5975);
FORCEPROP 2 LAST $SEC 1
J 0
(3800 6075);
DISPLAY 0.680851 (3800 6075);
PAINT MONO (3800 6075);
DISPLAY INVISIBLE (3800 6075);
FORCEPROP 2 LAST CDS_SEC 1
J 0
(3800 6075);
DISPLAY 1.021277 (3800 6075);
DISPLAY INVISIBLE (3800 6075);
FORCEPROP 1 LASTPIN (3750 5975) $PN 1
J 0
(3760 5955);
DISPLAY 0.787234 (3760 5955);
FORCEPROP 1 LASTPIN (3750 5775) $PN 2
J 0
(3760 5755);
DISPLAY 0.787234 (3760 5755);
FORCEPROP 1 LAST VALUE 0.1UF
J 0
(3800 5925);
DISPLAY 0.638298 (3800 5925);
FORCEPROP 1 LAST VOLTAGE 25V
J 0
(3800 5875);
DISPLAY 0.638298 (3800 5875);
FORCEPROP 1 LAST TOLERANCE 10%
J 0
(3800 5825);
DISPLAY 0.638298 (3800 5825);
FORCEPROP 1 LAST MATERIAL X7R
J 0
(3800 5775);
DISPLAY 0.638298 (3800 5775);
FORCEPROP 2 LAST ROOM PCIE REDRIVER BOM1
J 0
(3800 6025);
DISPLAY 0.446809 (3800 6025);
PAINT RED (3800 6025);
FORCEPROP 1 LAST PACK_TYPE 0402
J 0
(3800 5725);
DISPLAY 0.638298 (3800 5725);
FORCEPROP 2 LAST CDS_LIB pure_quanta
J 0
(3750 5875);
PAINT MONO (3750 5875);
DISPLAY INVISIBLE (3750 5875);
FORCEPROP 1 LAST PATH I64
J 0
(3800 6025);
DISPLAY 0.978723 (3800 6025);
PAINT WHITE (3800 6025);
DISPLAY INVISIBLE (3800 6025);
FORCEPROP 1 LAST PART_NUMBER CH4104K1B00
J 0
(3800 5725);
DISPLAY 0.808511 (3800 5725);
DISPLAY INVISIBLE (3800 5725);
FORCEADD Q_CAP..1
(4225 5875);
FORCEPROP 1 LAST LOCATION C1866
J 0
(4275 5975);
DISPLAY 0.978723 (4275 5975);
FORCEPROP 0 LAST $SEC 1
J 0
(4275 6025);
DISPLAY 0.680851 (4275 6025);
PAINT MONO (4275 6025);
DISPLAY INVISIBLE (4275 6025);
FORCEPROP 0 LAST CDS_SEC 1
J 0
(4275 6025);
DISPLAY 1.021277 (4275 6025);
DISPLAY INVISIBLE (4275 6025);
FORCEPROP 1 LASTPIN (4225 5975) $PN 1
J 0
(4235 5955);
DISPLAY 0.787234 (4235 5955);
PAINT MONO (4235 5955);
FORCEPROP 1 LASTPIN (4225 5775) $PN 2
J 0
(4235 5755);
DISPLAY 0.787234 (4235 5755);
PAINT MONO (4235 5755);
FORCEPROP 1 LAST MATERIAL X7R
J 0
(4275 5775);
DISPLAY 0.638298 (4275 5775);
FORCEPROP 1 LAST VALUE 0.1UF
J 0
(4275 5925);
DISPLAY 0.638298 (4275 5925);
FORCEPROP 1 LAST PACK_TYPE 0402
J 0
(4275 5725);
DISPLAY 0.638298 (4275 5725);
FORCEPROP 2 LAST ROOM PCIE REDRIVER BOM1
J 0
(4250 6025);
DISPLAY 0.446809 (4250 6025);
PAINT RED (4250 6025);
FORCEPROP 1 LAST VOLTAGE 25V
J 0
(4275 5875);
DISPLAY 0.638298 (4275 5875);
FORCEPROP 1 LAST TOLERANCE 10%
J 0
(4275 5825);
DISPLAY 0.638298 (4275 5825);
FORCEPROP 2 LAST CDS_LIB pure_quanta
J 0
(4225 5875);
DISPLAY INVISIBLE (4225 5875);
FORCEPROP 1 LAST PATH I65
J 0
(4275 6025);
DISPLAY 0.978723 (4275 6025);
PAINT WHITE (4275 6025);
DISPLAY INVISIBLE (4275 6025);
FORCEPROP 1 LAST PART_NUMBER CH4104K1B00
J 0
(4275 5725);
DISPLAY 0.808511 (4275 5725);
DISPLAY INVISIBLE (4275 5725);
FORCEADD UNIVERSAL_POWER..1
(4625 6275);
FORCEPROP 3 LASTPIN (4625 6225) SIG_NAME P3V3_AUX\g
J 0
(4635 6235);
DISPLAY 0.659574 (4635 6235);
PAINT MONO (4635 6235);
DISPLAY INVISIBLE (4635 6235);
FORCEPROP 1 LAST HDL_POWER P3V3_AUX
J 1
(4625 6325);
DISPLAY 0.872340 (4625 6325);
PAINT GREEN (4625 6325);
FORCEPROP 2 LAST CDS_LIB pure_quanta_power
J 0
(4625 6275);
DISPLAY INVISIBLE (4625 6275);
FORCEPROP 1 LAST PATH I66
J 0
(4675 6300);
DISPLAY 0.872340 (4675 6300);
PAINT AQUA (4675 6300);
DISPLAY INVISIBLE (4675 6300);
FORCEADD Q_RES..1
(6250 5025);
FORCEPROP 1 LAST LOCATION R4537
J 0
(6200 5075);
DISPLAY 0.978723 (6200 5075);
FORCEPROP 0 LAST $SEC 1
J 0
(6200 5125);
DISPLAY 0.680851 (6200 5125);
PAINT MONO (6200 5125);
DISPLAY INVISIBLE (6200 5125);
FORCEPROP 0 LAST CDS_SEC 1
J 0
(6200 5125);
DISPLAY 1.021277 (6200 5125);
DISPLAY INVISIBLE (6200 5125);
FORCEPROP 1 LASTPIN (6150 5025) $PN 1
J 0
(6162 5037);
DISPLAY 0.787234 (6162 5037);
PAINT MONO (6162 5037);
FORCEPROP 1 LASTPIN (6350 5025) $PN 2
J 0
(6312 5037);
DISPLAY 0.787234 (6312 5037);
PAINT MONO (6312 5037);
FORCEPROP 1 LAST PACK_TYPE 0402LF
J 0
(6550 5025);
DISPLAY 0.574468 (6550 5025);
FORCEPROP 1 LAST MATERIAL CHIP
J 0
(6425 5025);
DISPLAY 0.574468 (6425 5025);
FORCEPROP 1 LAST VALUE 0
J 2
(6400 5025);
DISPLAY 0.574468 (6400 5025);
FORCEPROP 2 LAST ROOM PCIE REDRIVER BOM1
J 0
(6025 4975);
DISPLAY 0.553191 (6025 4975);
PAINT RED (6025 4975);
FORCEPROP 1 LAST WATTAGE 1/16W
J 2
(6325 4950);
DISPLAY 0.723404 (6325 4950);
PAINT SKYBLUE (6325 4950);
DISPLAY INVISIBLE (6325 4950);
FORCEPROP 1 LAST TOLERANCE 5%
J 0
(6050 4950);
DISPLAY 0.723404 (6050 4950);
PAINT SKYBLUE (6050 4950);
DISPLAY INVISIBLE (6050 4950);
FORCEPROP 2 LAST CDS_LIB pure_quanta
J 0
(6250 5025);
DISPLAY INVISIBLE (6250 5025);
FORCEPROP 1 LAST PATH I67
J 0
(6200 5175);
DISPLAY 0.978723 (6200 5175);
PAINT WHITE (6200 5175);
DISPLAY INVISIBLE (6200 5175);
FORCEPROP 1 LAST PART_NUMBER CS00002JB13
J 0
(5975 4900);
DISPLAY 0.723404 (5975 4900);
PAINT WHITE (5975 4900);
DISPLAY INVISIBLE (5975 4900);
FORCEADD OFFPAGE..4
(6600 5325);
FORCEPROP 2 LAST $XR0 111 
J 0
(6786 5325);
DISPLAY 0.638298 (6786 5325);
PAINT MONO (6786 5325);
FORCEPROP 2 LAST CDS_LIB standard
J 0
(6600 5325);
DISPLAY INVISIBLE (6600 5325);
FORCEPROP 1 LAST OFFPAGE TRUE
J 0
(6925 5200);
DISPLAY 0.872340 (6925 5200);
PAINT GREEN (6925 5200);
DISPLAY INVISIBLE (6925 5200);
FORCEPROP 1 LAST COMMENT_BODY TRUE
J 0
(6575 5225);
DISPLAY 0.872340 (6575 5225);
PAINT GREEN (6575 5225);
DISPLAY INVISIBLE (6575 5225);
FORCEPROP 2 LAST PATH I68
J 0
(6800 5375);
DISPLAY 0.680851 (6800 5375);
DISPLAY INVISIBLE (6800 5375);
FORCEADD UNIVERSAL_GND..1
(2000 2375);
FORCEPROP 3 LASTPIN (2000 2425) SIG_NAME GND\g
J 0
(2010 2435);
DISPLAY 0.659574 (2010 2435);
PAINT MONO (2010 2435);
DISPLAY INVISIBLE (2010 2435);
FORCEPROP 2 LAST ROOM IO_SLOT
J 1
(1875 2425);
DISPLAY 0.744681 (1875 2425);
FORCEPROP 2 LAST CDS_LIB pure_quanta_power
J 0
(2000 2375);
DISPLAY INVISIBLE (2000 2375);
FORCEPROP 1 LAST HDL_POWER GND
J 1
(2025 2300);
DISPLAY 0.872340 (2025 2300);
PAINT GREEN (2025 2300);
DISPLAY INVISIBLE (2025 2300);
FORCEPROP 1 LAST PATH I7
J 0
(2075 2375);
DISPLAY 0.872340 (2075 2375);
PAINT AQUA (2075 2375);
DISPLAY INVISIBLE (2075 2375);
FORCEADD UNIVERSAL_GND..1
(7300 2375);
FORCEPROP 3 LASTPIN (7300 2425) SIG_NAME GND\g
J 0
(7310 2435);
DISPLAY 0.659574 (7310 2435);
PAINT MONO (7310 2435);
DISPLAY INVISIBLE (7310 2435);
FORCEPROP 2 LAST ROOM IO_SLOT
J 1
(7075 2450);
DISPLAY 0.744681 (7075 2450);
FORCEPROP 2 LAST CDS_LIB pure_quanta_power
J 0
(7300 2375);
DISPLAY INVISIBLE (7300 2375);
FORCEPROP 1 LAST HDL_POWER GND
J 1
(7325 2300);
DISPLAY 0.872340 (7325 2300);
PAINT GREEN (7325 2300);
DISPLAY INVISIBLE (7325 2300);
FORCEPROP 1 LAST PATH I73
J 0
(7375 2375);
DISPLAY 0.872340 (7375 2375);
PAINT AQUA (7375 2375);
DISPLAY INVISIBLE (7375 2375);
FORCEADD Q_RES..2
(7300 2700);
FORCEPROP 1 LAST LOCATION R3288
J 0
(7345 2825);
DISPLAY 0.978723 (7345 2825);
FORCEPROP 0 LAST $SEC 1
J 0
(7350 2875);
DISPLAY 0.680851 (7350 2875);
PAINT MONO (7350 2875);
DISPLAY INVISIBLE (7350 2875);
FORCEPROP 0 LAST CDS_SEC 1
J 0
(7350 2875);
DISPLAY 1.021277 (7350 2875);
DISPLAY INVISIBLE (7350 2875);
FORCEPROP 1 LASTPIN (7300 2800) $PN 1
J 0
(7305 2762);
DISPLAY 0.787234 (7305 2762);
PAINT MONO (7305 2762);
FORCEPROP 1 LASTPIN (7300 2600) $PN 2
J 0
(7305 2610);
DISPLAY 0.787234 (7305 2610);
PAINT MONO (7305 2610);
FORCEPROP 2 LAST ROOM PCIE REDRIVER BOM1
J 0
(7350 2875);
DISPLAY 0.361702 (7350 2875);
PAINT RED (7350 2875);
FORCEPROP 1 LAST WATTAGE 1/16W
J 0
(7340 2675);
DISPLAY 0.638298 (7340 2675);
FORCEPROP 1 LAST VALUE 68K
J 0
(7345 2775);
DISPLAY 0.638298 (7345 2775);
FORCEPROP 1 LAST TOLERANCE 1%
J 0
(7345 2725);
DISPLAY 0.638298 (7345 2725);
FORCEPROP 1 LAST PACK_TYPE 0402LF
J 0
(7340 2525);
DISPLAY 0.638298 (7340 2525);
FORCEPROP 1 LAST MATERIAL EMPTY
J 0
(7340 2625);
DISPLAY 0.638298 (7340 2625);
PAINT RED (7340 2625);
FORCEPROP 2 LAST CDS_LIB pure_quanta
J 0
(7300 2700);
DISPLAY INVISIBLE (7300 2700);
FORCEPROP 1 LAST PATH I74
J 0
(7350 2875);
DISPLAY 0.978723 (7350 2875);
PAINT WHITE (7350 2875);
DISPLAY INVISIBLE (7350 2875);
FORCEPROP 1 LAST PART_NUMBER CS36802FB04
J 0
(7340 2575);
DISPLAY 0.638298 (7340 2575);
DISPLAY INVISIBLE (7340 2575);
FORCEADD UNIVERSAL_GND..1
(7700 2375);
FORCEPROP 3 LASTPIN (7700 2425) SIG_NAME GND\g
J 0
(7710 2435);
DISPLAY 0.659574 (7710 2435);
PAINT MONO (7710 2435);
DISPLAY INVISIBLE (7710 2435);
FORCEPROP 2 LAST ROOM IO_SLOT
J 1
(7475 2450);
DISPLAY 0.744681 (7475 2450);
FORCEPROP 2 LAST CDS_LIB pure_quanta_power
J 0
(7700 2375);
DISPLAY INVISIBLE (7700 2375);
FORCEPROP 1 LAST HDL_POWER GND
J 1
(7725 2300);
DISPLAY 0.872340 (7725 2300);
PAINT GREEN (7725 2300);
DISPLAY INVISIBLE (7725 2300);
FORCEPROP 1 LAST PATH I75
J 0
(7775 2375);
DISPLAY 0.872340 (7775 2375);
PAINT AQUA (7775 2375);
DISPLAY INVISIBLE (7775 2375);
FORCEADD Q_RES..2
(7700 2675);
FORCEPROP 1 LAST LOCATION R3290
J 0
(7745 2800);
DISPLAY 0.978723 (7745 2800);
FORCEPROP 0 LAST $SEC 1
J 0
(7750 2850);
DISPLAY 0.680851 (7750 2850);
PAINT MONO (7750 2850);
DISPLAY INVISIBLE (7750 2850);
FORCEPROP 0 LAST CDS_SEC 1
J 0
(7750 2850);
DISPLAY 1.021277 (7750 2850);
DISPLAY INVISIBLE (7750 2850);
FORCEPROP 1 LASTPIN (7700 2775) $PN 1
J 0
(7705 2737);
DISPLAY 0.787234 (7705 2737);
PAINT MONO (7705 2737);
FORCEPROP 1 LASTPIN (7700 2575) $PN 2
J 0
(7705 2585);
DISPLAY 0.787234 (7705 2585);
PAINT MONO (7705 2585);
FORCEPROP 1 LAST VALUE 1K
J 0
(7745 2750);
DISPLAY 0.638298 (7745 2750);
FORCEPROP 2 LAST ROOM PCIE REDRIVER BOM1
J 0
(7750 2850);
DISPLAY 0.553191 (7750 2850);
PAINT RED (7750 2850);
FORCEPROP 1 LAST WATTAGE 1/16W
J 0
(7740 2650);
DISPLAY 0.638298 (7740 2650);
FORCEPROP 1 LAST MATERIAL EMPTY
J 0
(7740 2600);
DISPLAY 0.638298 (7740 2600);
PAINT RED (7740 2600);
FORCEPROP 1 LAST PACK_TYPE 0402LF
J 0
(7740 2500);
DISPLAY 0.638298 (7740 2500);
FORCEPROP 1 LAST TOLERANCE 1%
J 0
(7745 2700);
DISPLAY 0.638298 (7745 2700);
FORCEPROP 2 LAST CDS_LIB pure_quanta
J 0
(7700 2675);
DISPLAY INVISIBLE (7700 2675);
FORCEPROP 1 LAST PATH I76
J 0
(7750 2850);
DISPLAY 0.978723 (7750 2850);
PAINT WHITE (7750 2850);
DISPLAY INVISIBLE (7750 2850);
FORCEPROP 1 LAST PART_NUMBER CS21002FB06
J 0
(7740 2550);
DISPLAY 0.638298 (7740 2550);
DISPLAY INVISIBLE (7740 2550);
FORCEADD Q_RES..2
(7700 3250);
FORCEPROP 1 LAST LOCATION R3289
J 0
(7745 3375);
DISPLAY 0.978723 (7745 3375);
FORCEPROP 0 LAST $SEC 1
J 0
(7750 3425);
DISPLAY 0.680851 (7750 3425);
PAINT MONO (7750 3425);
DISPLAY INVISIBLE (7750 3425);
FORCEPROP 0 LAST CDS_SEC 1
J 0
(7750 3425);
DISPLAY 1.021277 (7750 3425);
DISPLAY INVISIBLE (7750 3425);
FORCEPROP 1 LASTPIN (7700 3350) $PN 1
J 0
(7705 3312);
DISPLAY 0.787234 (7705 3312);
PAINT MONO (7705 3312);
FORCEPROP 1 LASTPIN (7700 3150) $PN 2
J 0
(7705 3160);
DISPLAY 0.787234 (7705 3160);
PAINT MONO (7705 3160);
FORCEPROP 1 LAST VALUE 1K
J 0
(7745 3325);
DISPLAY 0.638298 (7745 3325);
FORCEPROP 2 LAST ROOM PCIE REDRIVER BOM1
J 0
(7750 3425);
DISPLAY 0.553191 (7750 3425);
PAINT RED (7750 3425);
FORCEPROP 1 LAST TOLERANCE 1%
J 0
(7745 3275);
DISPLAY 0.638298 (7745 3275);
FORCEPROP 1 LAST WATTAGE 1/16W
J 0
(7740 3225);
DISPLAY 0.638298 (7740 3225);
FORCEPROP 1 LAST MATERIAL EMPTY
J 0
(7740 3175);
DISPLAY 0.638298 (7740 3175);
PAINT RED (7740 3175);
FORCEPROP 1 LAST PACK_TYPE 0402LF
J 0
(7740 3075);
DISPLAY 0.638298 (7740 3075);
FORCEPROP 2 LAST CDS_LIB pure_quanta
J 0
(7700 3250);
DISPLAY INVISIBLE (7700 3250);
FORCEPROP 1 LAST PATH I77
J 0
(7750 3425);
DISPLAY 0.978723 (7750 3425);
PAINT WHITE (7750 3425);
DISPLAY INVISIBLE (7750 3425);
FORCEPROP 1 LAST PART_NUMBER CS21002FB06
J 0
(7740 3125);
DISPLAY 0.638298 (7740 3125);
DISPLAY INVISIBLE (7740 3125);
FORCEADD OFFPAGE..2
(8175 3000);
FORCEPROP 2 LAST $XR0 111 
J 0
(8364 3000);
DISPLAY 0.638298 (8364 3000);
PAINT MONO (8364 3000);
FORCEPROP 2 LAST CDS_LIB standard
J 0
(8175 3000);
DISPLAY INVISIBLE (8175 3000);
FORCEPROP 1 LAST OFFPAGE TRUE
J 0
(8500 2875);
DISPLAY 0.872340 (8500 2875);
PAINT GREEN (8500 2875);
DISPLAY INVISIBLE (8500 2875);
FORCEPROP 1 LAST COMMENT_BODY TRUE
J 0
(8130 2905);
DISPLAY 0.872340 (8130 2905);
PAINT GREEN (8130 2905);
DISPLAY INVISIBLE (8130 2905);
FORCEPROP 2 LAST PATH I78
J 0
(8375 3050);
DISPLAY 0.680851 (8375 3050);
DISPLAY INVISIBLE (8375 3050);
FORCEADD OFFPAGE..2
(8175 2950);
FORCEPROP 2 LAST $XR0 111 
J 0
(8364 2950);
DISPLAY 0.638298 (8364 2950);
PAINT MONO (8364 2950);
FORCEPROP 2 LAST CDS_LIB standard
J 0
(8175 2950);
DISPLAY INVISIBLE (8175 2950);
FORCEPROP 1 LAST OFFPAGE TRUE
J 0
(8500 2825);
DISPLAY 0.872340 (8500 2825);
PAINT GREEN (8500 2825);
DISPLAY INVISIBLE (8500 2825);
FORCEPROP 1 LAST COMMENT_BODY TRUE
J 0
(8130 2855);
DISPLAY 0.872340 (8130 2855);
PAINT GREEN (8130 2855);
DISPLAY INVISIBLE (8130 2855);
FORCEPROP 2 LAST PATH I79
J 0
(8375 3000);
DISPLAY 0.680851 (8375 3000);
DISPLAY INVISIBLE (8375 3000);
FORCEADD Q_RES..2
(2000 2725);
FORCEPROP 1 LAST LOCATION R3267
J 0
(2045 2850);
DISPLAY 0.638298 (2045 2850);
FORCEPROP 0 LAST $SEC 1
J 0
(2050 2900);
DISPLAY 0.680851 (2050 2900);
PAINT MONO (2050 2900);
DISPLAY INVISIBLE (2050 2900);
FORCEPROP 0 LAST CDS_SEC 1
J 0
(2050 2900);
DISPLAY 1.021277 (2050 2900);
DISPLAY INVISIBLE (2050 2900);
FORCEPROP 1 LASTPIN (2000 2825) $PN 1
J 0
(2005 2787);
DISPLAY 0.787234 (2005 2787);
PAINT MONO (2005 2787);
FORCEPROP 1 LASTPIN (2000 2625) $PN 2
J 0
(2005 2635);
DISPLAY 0.787234 (2005 2635);
PAINT MONO (2005 2635);
FORCEPROP 2 LAST ROOM PCIE REDRIVER BOM1
J 0
(2025 2900);
DISPLAY 0.361702 (2025 2900);
PAINT RED (2025 2900);
FORCEPROP 1 LAST MATERIAL EMPTY
J 0
(2040 2650);
DISPLAY 0.638298 (2040 2650);
PAINT RED (2040 2650);
FORCEPROP 1 LAST WATTAGE 1/16W
J 0
(2040 2700);
DISPLAY 0.638298 (2040 2700);
FORCEPROP 1 LAST TOLERANCE 1%
J 0
(2045 2750);
DISPLAY 0.638298 (2045 2750);
FORCEPROP 1 LAST VALUE 68K
J 0
(2045 2800);
DISPLAY 0.638298 (2045 2800);
FORCEPROP 1 LAST PACK_TYPE 0402LF
J 0
(2040 2550);
DISPLAY 0.638298 (2040 2550);
FORCEPROP 2 LAST CDS_LIB pure_quanta
J 0
(2000 2725);
DISPLAY INVISIBLE (2000 2725);
FORCEPROP 1 LAST PATH I8
J 0
(2050 2900);
DISPLAY 0.978723 (2050 2900);
PAINT WHITE (2050 2900);
DISPLAY INVISIBLE (2050 2900);
FORCEPROP 1 LAST PART_NUMBER CS36802FB04
J 0
(2040 2600);
DISPLAY 0.638298 (2040 2600);
DISPLAY INVISIBLE (2040 2600);
FORCEADD UNIVERSAL_GND..1
(9575 3700);
FORCEPROP 3 LASTPIN (9575 3750) SIG_NAME GND\g
J 0
(9585 3760);
DISPLAY 0.659574 (9585 3760);
PAINT MONO (9585 3760);
DISPLAY INVISIBLE (9585 3760);
FORCEPROP 2 LAST ROOM IO_SLOT
J 1
(9350 3775);
DISPLAY 0.744681 (9350 3775);
FORCEPROP 2 LAST CDS_LIB pure_quanta_power
J 0
(9575 3700);
PAINT MONO (9575 3700);
DISPLAY INVISIBLE (9575 3700);
FORCEPROP 1 LAST HDL_POWER GND
J 1
(9600 3625);
DISPLAY 0.872340 (9600 3625);
PAINT GREEN (9600 3625);
DISPLAY INVISIBLE (9600 3625);
FORCEPROP 1 LAST PATH I80
J 0
(9650 3700);
DISPLAY 0.872340 (9650 3700);
PAINT AQUA (9650 3700);
DISPLAY INVISIBLE (9650 3700);
FORCEADD Q_RES..2
(9575 3925);
FORCEPROP 1 LAST LOCATION R3265
J 0
(9620 4050);
DISPLAY 0.978723 (9620 4050);
FORCEPROP 2 LAST $SEC 1
J 0
(9625 4150);
DISPLAY 0.680851 (9625 4150);
PAINT MONO (9625 4150);
DISPLAY INVISIBLE (9625 4150);
FORCEPROP 2 LAST CDS_SEC 1
J 0
(9625 4150);
DISPLAY 1.021277 (9625 4150);
DISPLAY INVISIBLE (9625 4150);
FORCEPROP 1 LASTPIN (9575 4025) $PN 1
J 0
(9580 3987);
DISPLAY 0.787234 (9580 3987);
FORCEPROP 1 LASTPIN (9575 3825) $PN 2
J 0
(9580 3835);
DISPLAY 0.787234 (9580 3835);
FORCEPROP 1 LAST MATERIAL EMPTY
J 0
(9615 3850);
DISPLAY 0.787234 (9615 3850);
PAINT RED (9615 3850);
FORCEPROP 1 LAST WATTAGE 1/16W
J 0
(9615 3900);
DISPLAY 0.787234 (9615 3900);
FORCEPROP 1 LAST VALUE 4.7K
J 0
(9620 4000);
DISPLAY 0.787234 (9620 4000);
FORCEPROP 1 LAST TOLERANCE 1%
J 0
(9620 3950);
DISPLAY 0.787234 (9620 3950);
FORCEPROP 1 LAST PACK_TYPE 0402LF
J 0
(9615 3750);
DISPLAY 0.787234 (9615 3750);
FORCEPROP 2 LAST ROOM PCIE REDRIVER BOM1
J 0
(9625 4100);
DISPLAY 0.680851 (9625 4100);
PAINT RED (9625 4100);
FORCEPROP 2 LAST CDS_LIB pure_quanta
J 0
(9575 3925);
PAINT MONO (9575 3925);
DISPLAY INVISIBLE (9575 3925);
FORCEPROP 1 LAST PATH I81
J 0
(9625 4100);
DISPLAY 0.978723 (9625 4100);
PAINT WHITE (9625 4100);
DISPLAY INVISIBLE (9625 4100);
FORCEPROP 1 LAST PART_NUMBER CS24702FB06
J 0
(9615 3800);
DISPLAY 0.787234 (9615 3800);
DISPLAY INVISIBLE (9615 3800);
FORCEADD OFFPAGE..4
(7625 5025);
FORCEPROP 2 LAST $XR2 112 
J 0
(8051 5025);
DISPLAY 0.638298 (8051 5025);
PAINT MONO (8051 5025);
FORCEPROP 2 LAST $XR1 234 
J 0
(7931 5025);
DISPLAY 0.638298 (7931 5025);
PAINT MONO (7931 5025);
FORCEPROP 2 LAST $XR0 111 
J 0
(7811 5025);
DISPLAY 0.638298 (7811 5025);
PAINT MONO (7811 5025);
FORCEPROP 2 LAST CDS_LIB standard
J 0
(7625 5025);
DISPLAY INVISIBLE (7625 5025);
FORCEPROP 1 LAST OFFPAGE TRUE
J 0
(7950 4900);
DISPLAY 0.872340 (7950 4900);
PAINT GREEN (7950 4900);
DISPLAY INVISIBLE (7950 4900);
FORCEPROP 1 LAST COMMENT_BODY TRUE
J 0
(7600 4925);
DISPLAY 0.872340 (7600 4925);
PAINT GREEN (7600 4925);
DISPLAY INVISIBLE (7600 4925);
FORCEPROP 2 LAST PATH I82
J 0
(7950 5075);
DISPLAY 0.680851 (7950 5075);
DISPLAY INVISIBLE (7950 5075);
FORCEADD OFFPAGE..2
(6675 5475);
FORCEPROP 2 LAST $XR0 113 
J 0
(6864 5475);
DISPLAY 0.638298 (6864 5475);
PAINT MONO (6864 5475);
FORCEPROP 2 LAST CDS_LIB standard
J 2
(6675 5475);
DISPLAY INVISIBLE (6675 5475);
FORCEPROP 1 LAST OFFPAGE TRUE
J 0
(7000 5350);
DISPLAY 0.872340 (7000 5350);
PAINT AQUA (7000 5350);
DISPLAY INVISIBLE (7000 5350);
FORCEPROP 1 LAST COMMENT_BODY TRUE
J 0
(6630 5380);
DISPLAY 0.872340 (6630 5380);
PAINT GREEN (6630 5380);
DISPLAY INVISIBLE (6630 5380);
FORCEPROP 2 LAST PATH I83
J 0
(6875 5525);
DISPLAY 0.680851 (6875 5525);
DISPLAY INVISIBLE (6875 5525);
FORCEADD OFFPAGE..2
(6675 5525);
FORCEPROP 2 LAST $XR0 113 
J 0
(6864 5525);
DISPLAY 0.638298 (6864 5525);
PAINT MONO (6864 5525);
FORCEPROP 2 LAST CDS_LIB standard
J 0
(6675 5525);
DISPLAY INVISIBLE (6675 5525);
FORCEPROP 1 LAST OFFPAGE TRUE
J 0
(7000 5400);
DISPLAY 0.872340 (7000 5400);
PAINT AQUA (7000 5400);
DISPLAY INVISIBLE (7000 5400);
FORCEPROP 1 LAST COMMENT_BODY TRUE
J 0
(6630 5430);
DISPLAY 0.872340 (6630 5430);
PAINT GREEN (6630 5430);
DISPLAY INVISIBLE (6630 5430);
FORCEPROP 2 LAST PATH I84
J 0
(6875 5575);
DISPLAY 0.680851 (6875 5575);
DISPLAY INVISIBLE (6875 5575);
FORCEADD OFFPAGE..2
(6675 5675);
FORCEPROP 2 LAST $XR0 113 
J 0
(6864 5675);
DISPLAY 0.638298 (6864 5675);
PAINT MONO (6864 5675);
FORCEPROP 2 LAST CDS_LIB standard
J 0
(6675 5675);
DISPLAY INVISIBLE (6675 5675);
FORCEPROP 1 LAST OFFPAGE TRUE
J 0
(7000 5550);
DISPLAY 0.872340 (7000 5550);
PAINT AQUA (7000 5550);
DISPLAY INVISIBLE (7000 5550);
FORCEPROP 1 LAST COMMENT_BODY TRUE
J 0
(6630 5580);
DISPLAY 0.872340 (6630 5580);
PAINT GREEN (6630 5580);
DISPLAY INVISIBLE (6630 5580);
FORCEPROP 2 LAST PATH I85
J 0
(6875 5725);
DISPLAY 0.680851 (6875 5725);
DISPLAY INVISIBLE (6875 5725);
FORCEADD OFFPAGE..2
(6675 5725);
FORCEPROP 2 LAST $XR0 113 
J 0
(6864 5725);
DISPLAY 0.638298 (6864 5725);
PAINT MONO (6864 5725);
FORCEPROP 2 LAST CDS_LIB standard
J 2
(6675 5725);
DISPLAY INVISIBLE (6675 5725);
FORCEPROP 1 LAST OFFPAGE TRUE
J 0
(7000 5600);
DISPLAY 0.872340 (7000 5600);
PAINT AQUA (7000 5600);
DISPLAY INVISIBLE (7000 5600);
FORCEPROP 1 LAST COMMENT_BODY TRUE
J 0
(6630 5630);
DISPLAY 0.872340 (6630 5630);
PAINT GREEN (6630 5630);
DISPLAY INVISIBLE (6630 5630);
FORCEPROP 2 LAST PATH I86
J 0
(6875 5775);
DISPLAY 0.680851 (6875 5775);
DISPLAY INVISIBLE (6875 5775);
FORCEADD UNIVERSAL_GND..1
(8350 4675);
FORCEPROP 3 LASTPIN (8350 4725) SIG_NAME GND\g
J 0
(8360 4735);
DISPLAY 0.659574 (8360 4735);
PAINT MONO (8360 4735);
DISPLAY INVISIBLE (8360 4735);
FORCEPROP 2 LAST ROOM IO_SLOT
J 1
(8125 4750);
DISPLAY 0.744681 (8125 4750);
FORCEPROP 2 LAST CDS_LIB pure_quanta_power
J 0
(8350 4675);
DISPLAY INVISIBLE (8350 4675);
FORCEPROP 1 LAST HDL_POWER GND
J 1
(8375 4600);
DISPLAY 0.872340 (8375 4600);
PAINT GREEN (8375 4600);
DISPLAY INVISIBLE (8375 4600);
FORCEPROP 1 LAST PATH I87
J 0
(8425 4675);
DISPLAY 0.872340 (8425 4675);
PAINT AQUA (8425 4675);
DISPLAY INVISIBLE (8425 4675);
FORCEADD Q_RES..2
(8350 4900);
FORCEPROP 1 LAST LOCATION R3291
J 0
(8400 5025);
DISPLAY 0.978723 (8400 5025);
FORCEPROP 0 LAST $SEC 1
J 0
(8400 5075);
DISPLAY 0.680851 (8400 5075);
PAINT MONO (8400 5075);
DISPLAY INVISIBLE (8400 5075);
FORCEPROP 0 LAST CDS_SEC 1
J 0
(8400 5075);
DISPLAY 1.021277 (8400 5075);
DISPLAY INVISIBLE (8400 5075);
FORCEPROP 1 LASTPIN (8350 5000) $PN 1
J 0
(8355 4962);
DISPLAY 0.787234 (8355 4962);
PAINT MONO (8355 4962);
FORCEPROP 1 LASTPIN (8350 4800) $PN 2
J 0
(8355 4810);
DISPLAY 0.787234 (8355 4810);
PAINT MONO (8355 4810);
FORCEPROP 2 LAST ROOM PCIE REDRIVER BOM1
J 0
(8400 5075);
DISPLAY 0.553191 (8400 5075);
PAINT RED (8400 5075);
FORCEPROP 1 LAST WATTAGE 1/16W
J 0
(8390 4875);
DISPLAY 0.787234 (8390 4875);
FORCEPROP 1 LAST MATERIAL EMPTY
J 0
(8390 4825);
DISPLAY 0.787234 (8390 4825);
FORCEPROP 1 LAST PACK_TYPE 0402LF
J 0
(8390 4725);
DISPLAY 0.787234 (8390 4725);
FORCEPROP 1 LAST TOLERANCE 1%
J 0
(8395 4925);
DISPLAY 0.787234 (8395 4925);
FORCEPROP 1 LAST VALUE 4.7K
J 0
(8395 4975);
DISPLAY 0.787234 (8395 4975);
FORCEPROP 2 LAST CDS_LIB pure_quanta
J 0
(8350 4900);
DISPLAY INVISIBLE (8350 4900);
FORCEPROP 1 LAST PATH I88
J 0
(8400 5075);
DISPLAY 0.978723 (8400 5075);
PAINT WHITE (8400 5075);
DISPLAY INVISIBLE (8400 5075);
FORCEPROP 1 LAST PART_NUMBER CS24702FB06
J 0
(8390 4775);
DISPLAY 0.787234 (8390 4775);
DISPLAY INVISIBLE (8390 4775);
FORCEADD Q_RES..2
(9575 4450);
FORCEPROP 1 LAST LOCATION R3292
J 0
(9620 4575);
DISPLAY 0.978723 (9620 4575);
FORCEPROP 0 LAST $SEC 1
J 0
(9625 4625);
DISPLAY 0.680851 (9625 4625);
PAINT MONO (9625 4625);
DISPLAY INVISIBLE (9625 4625);
FORCEPROP 0 LAST CDS_SEC 1
J 0
(9625 4625);
DISPLAY 1.021277 (9625 4625);
DISPLAY INVISIBLE (9625 4625);
FORCEPROP 1 LASTPIN (9575 4550) $PN 1
J 0
(9580 4512);
DISPLAY 0.787234 (9580 4512);
PAINT MONO (9580 4512);
FORCEPROP 1 LASTPIN (9575 4350) $PN 2
J 0
(9580 4360);
DISPLAY 0.787234 (9580 4360);
PAINT MONO (9580 4360);
FORCEPROP 1 LAST MATERIAL CHIP
J 0
(9615 4375);
DISPLAY 0.787234 (9615 4375);
FORCEPROP 1 LAST VALUE 4.7K
J 0
(9620 4525);
DISPLAY 0.787234 (9620 4525);
FORCEPROP 1 LAST PACK_TYPE 0402LF
J 0
(9615 4275);
DISPLAY 0.787234 (9615 4275);
FORCEPROP 1 LAST TOLERANCE 1%
J 0
(9620 4475);
DISPLAY 0.787234 (9620 4475);
FORCEPROP 2 LAST ROOM PCIE REDRIVER BOM1
J 0
(9625 4625);
DISPLAY 0.680851 (9625 4625);
PAINT RED (9625 4625);
FORCEPROP 1 LAST WATTAGE 1/16W
J 0
(9615 4425);
DISPLAY 0.787234 (9615 4425);
FORCEPROP 2 LAST CDS_LIB pure_quanta
J 0
(9575 4450);
DISPLAY INVISIBLE (9575 4450);
FORCEPROP 1 LAST PATH I89
J 0
(9625 4625);
DISPLAY 0.978723 (9625 4625);
PAINT WHITE (9625 4625);
DISPLAY INVISIBLE (9625 4625);
FORCEPROP 1 LAST PART_NUMBER CS24702FB06
J 0
(9615 4325);
DISPLAY 0.787234 (9615 4325);
DISPLAY INVISIBLE (9615 4325);
FORCEADD Q_RES..2
(2375 2725);
FORCEPROP 1 LAST LOCATION R3270
J 0
(2420 2850);
DISPLAY 0.978723 (2420 2850);
FORCEPROP 0 LAST $SEC 1
J 0
(2425 2900);
DISPLAY 0.680851 (2425 2900);
PAINT MONO (2425 2900);
DISPLAY INVISIBLE (2425 2900);
FORCEPROP 0 LAST CDS_SEC 1
J 0
(2425 2900);
DISPLAY 1.021277 (2425 2900);
DISPLAY INVISIBLE (2425 2900);
FORCEPROP 1 LASTPIN (2375 2825) $PN 1
J 0
(2380 2787);
DISPLAY 0.787234 (2380 2787);
PAINT MONO (2380 2787);
FORCEPROP 1 LASTPIN (2375 2625) $PN 2
J 0
(2380 2635);
DISPLAY 0.787234 (2380 2635);
PAINT MONO (2380 2635);
FORCEPROP 1 LAST VALUE 1K
J 0
(2420 2800);
DISPLAY 0.638298 (2420 2800);
FORCEPROP 2 LAST ROOM PCIE REDRIVER BOM1
J 0
(2425 2900);
DISPLAY 0.446809 (2425 2900);
PAINT RED (2425 2900);
FORCEPROP 1 LAST MATERIAL EMPTY
J 0
(2415 2650);
DISPLAY 0.638298 (2415 2650);
PAINT RED (2415 2650);
FORCEPROP 1 LAST WATTAGE 1/16W
J 0
(2415 2700);
DISPLAY 0.638298 (2415 2700);
FORCEPROP 1 LAST TOLERANCE 1%
J 0
(2420 2750);
DISPLAY 0.638298 (2420 2750);
FORCEPROP 1 LAST PACK_TYPE 0402LF
J 0
(2415 2550);
DISPLAY 0.638298 (2415 2550);
FORCEPROP 2 LAST CDS_LIB pure_quanta
J 0
(2375 2725);
DISPLAY INVISIBLE (2375 2725);
FORCEPROP 1 LAST PATH I9
J 0
(2425 2900);
DISPLAY 0.978723 (2425 2900);
PAINT WHITE (2425 2900);
DISPLAY INVISIBLE (2425 2900);
FORCEPROP 1 LAST PART_NUMBER CS21002FB06
J 0
(2415 2600);
DISPLAY 0.638298 (2415 2600);
DISPLAY INVISIBLE (2415 2600);
FORCEADD UNIVERSAL_GND..1
(9600 5150);
FORCEPROP 3 LASTPIN (9600 5200) SIG_NAME GND\g
J 0
(9610 5210);
DISPLAY 0.659574 (9610 5210);
PAINT MONO (9610 5210);
DISPLAY INVISIBLE (9610 5210);
FORCEPROP 2 LAST ROOM IO_SLOT
J 1
(9375 5225);
DISPLAY 0.744681 (9375 5225);
FORCEPROP 2 LAST CDS_LIB pure_quanta_power
J 0
(9600 5150);
PAINT MONO (9600 5150);
DISPLAY INVISIBLE (9600 5150);
FORCEPROP 1 LAST HDL_POWER GND
J 1
(9625 5075);
DISPLAY 0.872340 (9625 5075);
PAINT GREEN (9625 5075);
DISPLAY INVISIBLE (9625 5075);
FORCEPROP 1 LAST PATH I90
J 0
(9675 5150);
DISPLAY 0.872340 (9675 5150);
PAINT AQUA (9675 5150);
DISPLAY INVISIBLE (9675 5150);
FORCEADD UNIVERSAL_POWER..1
(9575 4750);
FORCEPROP 3 LASTPIN (9575 4700) SIG_NAME P3V3_AUX\g
J 0
(9585 4710);
DISPLAY 0.659574 (9585 4710);
PAINT MONO (9585 4710);
DISPLAY INVISIBLE (9585 4710);
FORCEPROP 1 LAST HDL_POWER P3V3_AUX
J 1
(9575 4800);
DISPLAY 0.872340 (9575 4800);
PAINT GREEN (9575 4800);
FORCEPROP 2 LAST CDS_LIB pure_quanta_power
J 0
(9575 4750);
PAINT MONO (9575 4750);
DISPLAY INVISIBLE (9575 4750);
FORCEPROP 1 LAST PATH I91
J 0
(9625 4775);
DISPLAY 0.872340 (9625 4775);
PAINT AQUA (9625 4775);
DISPLAY INVISIBLE (9625 4775);
FORCEADD Q_RES..2
(9600 5375);
FORCEPROP 1 LAST LOCATION R3293
J 0
(9645 5500);
DISPLAY 0.978723 (9645 5500);
FORCEPROP 0 LAST $SEC 1
J 0
(9650 5550);
DISPLAY 0.680851 (9650 5550);
PAINT MONO (9650 5550);
DISPLAY INVISIBLE (9650 5550);
FORCEPROP 0 LAST CDS_SEC 1
J 0
(9650 5550);
DISPLAY 1.021277 (9650 5550);
DISPLAY INVISIBLE (9650 5550);
FORCEPROP 1 LASTPIN (9600 5475) $PN 1
J 0
(9605 5437);
DISPLAY 0.787234 (9605 5437);
PAINT MONO (9605 5437);
FORCEPROP 1 LASTPIN (9600 5275) $PN 2
J 0
(9605 5285);
DISPLAY 0.787234 (9605 5285);
PAINT MONO (9605 5285);
FORCEPROP 1 LAST MATERIAL EMPTY
J 0
(9640 5300);
DISPLAY 0.787234 (9640 5300);
FORCEPROP 1 LAST WATTAGE 1/16W
J 0
(9640 5350);
DISPLAY 0.787234 (9640 5350);
FORCEPROP 1 LAST TOLERANCE 1%
J 0
(9645 5400);
DISPLAY 0.787234 (9645 5400);
FORCEPROP 1 LAST VALUE 4.7K
J 0
(9645 5450);
DISPLAY 0.787234 (9645 5450);
FORCEPROP 1 LAST PACK_TYPE 0402LF
J 0
(9640 5200);
DISPLAY 0.787234 (9640 5200);
FORCEPROP 2 LAST ROOM PCIE REDRIVER BOM1
J 0
(9650 5550);
DISPLAY 0.680851 (9650 5550);
PAINT RED (9650 5550);
FORCEPROP 2 LAST CDS_LIB pure_quanta
J 0
(9600 5375);
DISPLAY INVISIBLE (9600 5375);
FORCEPROP 1 LAST PATH I92
J 0
(9650 5550);
DISPLAY 0.978723 (9650 5550);
PAINT WHITE (9650 5550);
DISPLAY INVISIBLE (9650 5550);
FORCEPROP 1 LAST PART_NUMBER CS24702FB06
J 0
(9640 5250);
DISPLAY 0.787234 (9640 5250);
DISPLAY INVISIBLE (9640 5250);
FORCEADD Q_RES..2
(9600 5900);
FORCEPROP 1 LAST LOCATION R3266
J 0
(9645 6025);
DISPLAY 0.978723 (9645 6025);
FORCEPROP 2 LAST $SEC 1
J 0
(9650 6125);
DISPLAY 0.680851 (9650 6125);
PAINT MONO (9650 6125);
DISPLAY INVISIBLE (9650 6125);
FORCEPROP 2 LAST CDS_SEC 1
J 0
(9650 6125);
DISPLAY 1.021277 (9650 6125);
DISPLAY INVISIBLE (9650 6125);
FORCEPROP 1 LASTPIN (9600 6000) $PN 1
J 0
(9605 5962);
DISPLAY 0.787234 (9605 5962);
FORCEPROP 1 LASTPIN (9600 5800) $PN 2
J 0
(9605 5810);
DISPLAY 0.787234 (9605 5810);
FORCEPROP 1 LAST PACK_TYPE 0402LF
J 0
(9640 5725);
DISPLAY 0.787234 (9640 5725);
FORCEPROP 1 LAST VALUE 4.7K
J 0
(9645 5975);
DISPLAY 0.787234 (9645 5975);
FORCEPROP 1 LAST MATERIAL CHIP
J 0
(9640 5825);
DISPLAY 0.787234 (9640 5825);
FORCEPROP 1 LAST WATTAGE 1/16W
J 0
(9640 5875);
DISPLAY 0.787234 (9640 5875);
FORCEPROP 2 LAST ROOM PCIE REDRIVER BOM1
J 0
(9650 6075);
DISPLAY 0.680851 (9650 6075);
PAINT RED (9650 6075);
FORCEPROP 1 LAST TOLERANCE 1%
J 0
(9645 5925);
DISPLAY 0.787234 (9645 5925);
FORCEPROP 2 LAST CDS_LIB pure_quanta
J 0
(9600 5900);
PAINT MONO (9600 5900);
DISPLAY INVISIBLE (9600 5900);
FORCEPROP 1 LAST PATH I93
J 0
(9650 6075);
DISPLAY 0.978723 (9650 6075);
PAINT WHITE (9650 6075);
DISPLAY INVISIBLE (9650 6075);
FORCEPROP 1 LAST PART_NUMBER CS24702FB06
J 0
(9640 5775);
DISPLAY 0.787234 (9640 5775);
DISPLAY INVISIBLE (9640 5775);
FORCEADD UNIVERSAL_POWER..1
(9600 6200);
FORCEPROP 3 LASTPIN (9600 6150) SIG_NAME P3V3_AUX\g
J 0
(9610 6160);
DISPLAY 0.659574 (9610 6160);
PAINT MONO (9610 6160);
DISPLAY INVISIBLE (9610 6160);
FORCEPROP 1 LAST HDL_POWER P3V3_AUX
J 1
(9600 6250);
DISPLAY 0.872340 (9600 6250);
PAINT GREEN (9600 6250);
FORCEPROP 2 LAST CDS_LIB pure_quanta_power
J 0
(9600 6200);
PAINT MONO (9600 6200);
DISPLAY INVISIBLE (9600 6200);
FORCEPROP 1 LAST PATH I94
J 0
(9650 6225);
DISPLAY 0.872340 (9650 6225);
PAINT AQUA (9650 6225);
DISPLAY INVISIBLE (9650 6225);
FORCEADD OFFPAGE..2
(10725 4225);
FORCEPROP 2 LAST $XR2 112 
J 0
(10914 4261);
DISPLAY 0.638298 (10914 4261);
PAINT MONO (10914 4261);
FORCEPROP 2 LAST $XR1 111 
J 0
(10914 4189);
DISPLAY 0.638298 (10914 4189);
PAINT MONO (10914 4189);
FORCEPROP 2 LAST $XR0 234 
J 0
(10914 4225);
DISPLAY 0.638298 (10914 4225);
PAINT MONO (10914 4225);
FORCEPROP 2 LAST CDS_LIB standard
J 0
(10725 4225);
PAINT MONO (10725 4225);
DISPLAY INVISIBLE (10725 4225);
FORCEPROP 1 LAST OFFPAGE TRUE
J 0
(11050 4100);
DISPLAY 0.872340 (11050 4100);
PAINT GREEN (11050 4100);
DISPLAY INVISIBLE (11050 4100);
FORCEPROP 1 LAST COMMENT_BODY TRUE
J 0
(10680 4130);
DISPLAY 0.872340 (10680 4130);
PAINT GREEN (10680 4130);
DISPLAY INVISIBLE (10680 4130);
FORCEPROP 2 LAST PATH I95
J 0
(11050 4275);
DISPLAY 0.680851 (11050 4275);
DISPLAY INVISIBLE (11050 4275);
FORCEADD OFFPAGE..2
(10325 5650);
FORCEPROP 2 LAST $XR0 111 
J 0
(10514 5650);
DISPLAY 0.638298 (10514 5650);
PAINT MONO (10514 5650);
FORCEPROP 2 LAST CDS_LIB standard
J 0
(10325 5650);
PAINT MONO (10325 5650);
DISPLAY INVISIBLE (10325 5650);
FORCEPROP 1 LAST OFFPAGE TRUE
J 0
(10650 5525);
DISPLAY 0.872340 (10650 5525);
PAINT GREEN (10650 5525);
DISPLAY INVISIBLE (10650 5525);
FORCEPROP 1 LAST COMMENT_BODY TRUE
J 0
(10280 5555);
DISPLAY 0.872340 (10280 5555);
PAINT GREEN (10280 5555);
DISPLAY INVISIBLE (10280 5555);
FORCEPROP 2 LAST PATH I96
J 0
(10525 5700);
DISPLAY 0.680851 (10525 5700);
DISPLAY INVISIBLE (10525 5700);
FORCEADD DNS..2
(3250 2650);
PAINT RED (3250 2650);
FORCEPROP 2 LAST CDS_LIB mstr_misc
J 0
(3250 2650);
DISPLAY INVISIBLE (3250 2650);
FORCEPROP 1 LAST COMMENT_BODY TRUE
R 1
J 0
(3325 2425);
DISPLAY 0.872340 (3325 2425);
PAINT GREEN (3325 2425);
DISPLAY INVISIBLE (3325 2425);
FORCEADD DNS..2
(3250 3225);
PAINT RED (3250 3225);
FORCEPROP 2 LAST CDS_LIB mstr_misc
J 0
(3250 3225);
DISPLAY INVISIBLE (3250 3225);
FORCEPROP 1 LAST COMMENT_BODY TRUE
R 1
J 0
(3325 3000);
DISPLAY 0.872340 (3325 3000);
PAINT GREEN (3325 3000);
DISPLAY INVISIBLE (3325 3000);
FORCEADD DNS..2
(2850 2675);
PAINT RED (2850 2675);
FORCEPROP 2 LAST CDS_LIB mstr_misc
J 0
(2850 2675);
DISPLAY INVISIBLE (2850 2675);
FORCEPROP 1 LAST COMMENT_BODY TRUE
R 1
J 0
(2925 2450);
DISPLAY 0.872340 (2925 2450);
PAINT GREEN (2925 2450);
DISPLAY INVISIBLE (2925 2450);
FORCEADD DNS..2
(5275 925);
PAINT RED (5275 925);
FORCEPROP 2 LAST CDS_LIB mstr_misc
J 0
(5275 925);
DISPLAY INVISIBLE (5275 925);
FORCEPROP 1 LAST COMMENT_BODY TRUE
R 1
J 0
(5350 700);
DISPLAY 0.872340 (5350 700);
PAINT GREEN (5350 700);
DISPLAY INVISIBLE (5350 700);
FORCEADD DNS..2
(5675 1475);
PAINT RED (5675 1475);
FORCEPROP 2 LAST CDS_LIB mstr_misc
J 0
(5675 1475);
DISPLAY INVISIBLE (5675 1475);
FORCEPROP 1 LAST COMMENT_BODY TRUE
R 1
J 0
(5750 1250);
DISPLAY 0.872340 (5750 1250);
PAINT GREEN (5750 1250);
DISPLAY INVISIBLE (5750 1250);
FORCEADD DNS..2
(6450 2700);
PAINT RED (6450 2700);
FORCEPROP 2 LAST CDS_LIB mstr_misc
J 0
(6450 2700);
DISPLAY INVISIBLE (6450 2700);
FORCEPROP 1 LAST COMMENT_BODY TRUE
R 1
J 0
(6525 2475);
DISPLAY 0.872340 (6525 2475);
PAINT GREEN (6525 2475);
DISPLAY INVISIBLE (6525 2475);
FORCEADD DNS..2
(6825 2700);
PAINT RED (6825 2700);
FORCEPROP 2 LAST CDS_LIB mstr_misc
J 0
(6825 2700);
DISPLAY INVISIBLE (6825 2700);
FORCEPROP 1 LAST COMMENT_BODY TRUE
R 1
J 0
(6900 2475);
DISPLAY 0.872340 (6900 2475);
PAINT GREEN (6900 2475);
DISPLAY INVISIBLE (6900 2475);
FORCEADD DNS..2
(6825 3225);
PAINT RED (6825 3225);
FORCEPROP 2 LAST CDS_LIB mstr_misc
J 0
(6825 3225);
DISPLAY INVISIBLE (6825 3225);
FORCEPROP 1 LAST COMMENT_BODY TRUE
R 1
J 0
(6900 3000);
DISPLAY 0.872340 (6900 3000);
PAINT GREEN (6900 3000);
DISPLAY INVISIBLE (6900 3000);
FORCEADD DNS..2
(7300 2675);
PAINT RED (7300 2675);
FORCEPROP 2 LAST CDS_LIB mstr_misc
J 0
(7300 2675);
DISPLAY INVISIBLE (7300 2675);
FORCEPROP 1 LAST COMMENT_BODY TRUE
R 1
J 0
(7375 2450);
DISPLAY 0.872340 (7375 2450);
PAINT GREEN (7375 2450);
DISPLAY INVISIBLE (7375 2450);
FORCEADD DNS..2
(7700 2650);
PAINT RED (7700 2650);
FORCEPROP 2 LAST CDS_LIB mstr_misc
J 0
(7700 2650);
DISPLAY INVISIBLE (7700 2650);
FORCEPROP 1 LAST COMMENT_BODY TRUE
R 1
J 0
(7775 2425);
DISPLAY 0.872340 (7775 2425);
PAINT GREEN (7775 2425);
DISPLAY INVISIBLE (7775 2425);
FORCEADD DNS..2
(2550 1500);
PAINT RED (2550 1500);
FORCEPROP 2 LAST CDS_LIB mstr_misc
J 0
(2550 1500);
DISPLAY INVISIBLE (2550 1500);
FORCEPROP 1 LAST COMMENT_BODY TRUE
R 1
J 0
(2625 1275);
DISPLAY 0.872340 (2625 1275);
PAINT GREEN (2625 1275);
DISPLAY INVISIBLE (2625 1275);
FORCEADD DNS..2
(9575 3900);
PAINT RED (9575 3900);
FORCEPROP 2 LAST CDS_LIB mstr_misc
J 0
(9575 3900);
DISPLAY INVISIBLE (9575 3900);
FORCEPROP 1 LAST COMMENT_BODY TRUE
R 1
J 0
(9650 3675);
DISPLAY 0.872340 (9650 3675);
PAINT GREEN (9650 3675);
DISPLAY INVISIBLE (9650 3675);
FORCEADD DNS..2
(4800 1475);
PAINT RED (4800 1475);
FORCEPROP 2 LAST CDS_LIB mstr_misc
J 0
(4800 1475);
DISPLAY INVISIBLE (4800 1475);
FORCEPROP 1 LAST COMMENT_BODY TRUE
R 1
J 0
(4875 1250);
DISPLAY 0.872340 (4875 1250);
PAINT GREEN (4875 1250);
DISPLAY INVISIBLE (4875 1250);
FORCEADD DNS..2
(4425 950);
PAINT RED (4425 950);
FORCEPROP 2 LAST CDS_LIB mstr_misc
J 0
(4425 950);
DISPLAY INVISIBLE (4425 950);
FORCEPROP 1 LAST COMMENT_BODY TRUE
R 1
J 0
(4500 725);
DISPLAY 0.872340 (4500 725);
PAINT GREEN (4500 725);
DISPLAY INVISIBLE (4500 725);
FORCEADD DNS..2
(2375 3225);
PAINT RED (2375 3225);
FORCEPROP 2 LAST CDS_LIB mstr_misc
J 0
(2375 3225);
DISPLAY INVISIBLE (2375 3225);
FORCEPROP 1 LAST COMMENT_BODY TRUE
R 1
J 0
(2450 3000);
DISPLAY 0.872340 (2450 3000);
PAINT GREEN (2450 3000);
DISPLAY INVISIBLE (2450 3000);
FORCEADD DNS..2
(2375 2700);
PAINT RED (2375 2700);
FORCEPROP 2 LAST CDS_LIB mstr_misc
J 0
(2375 2700);
DISPLAY INVISIBLE (2375 2700);
FORCEPROP 1 LAST COMMENT_BODY TRUE
R 1
J 0
(2450 2475);
DISPLAY 0.872340 (2450 2475);
PAINT GREEN (2450 2475);
DISPLAY INVISIBLE (2450 2475);
FORCEADD DNS..2
(2175 975);
PAINT RED (2175 975);
FORCEPROP 2 LAST CDS_LIB mstr_misc
J 0
(2175 975);
DISPLAY INVISIBLE (2175 975);
FORCEPROP 1 LAST COMMENT_BODY TRUE
R 1
J 0
(2250 750);
DISPLAY 0.872340 (2250 750);
PAINT GREEN (2250 750);
DISPLAY INVISIBLE (2250 750);
FORCEADD DNS..2
(4800 950);
PAINT RED (4800 950);
FORCEPROP 2 LAST CDS_LIB mstr_misc
J 0
(4800 950);
DISPLAY INVISIBLE (4800 950);
FORCEPROP 1 LAST COMMENT_BODY TRUE
R 1
J 0
(4875 725);
DISPLAY 0.872340 (4875 725);
PAINT GREEN (4875 725);
DISPLAY INVISIBLE (4875 725);
FORCEADD DNS..2
(2000 2700);
PAINT RED (2000 2700);
FORCEPROP 2 LAST CDS_LIB mstr_misc
J 0
(2000 2700);
DISPLAY INVISIBLE (2000 2700);
FORCEPROP 1 LAST COMMENT_BODY TRUE
R 1
J 0
(2075 2475);
DISPLAY 0.872340 (2075 2475);
PAINT GREEN (2075 2475);
DISPLAY INVISIBLE (2075 2475);
FORCEADD DNS..2
(8350 4875);
PAINT RED (8350 4875);
FORCEPROP 2 LAST CDS_LIB mstr_misc
J 0
(8350 4875);
DISPLAY INVISIBLE (8350 4875);
FORCEPROP 1 LAST COMMENT_BODY TRUE
R 1
J 0
(8425 4650);
DISPLAY 0.872340 (8425 4650);
PAINT GREEN (8425 4650);
DISPLAY INVISIBLE (8425 4650);
FORCEADD DNS..2
(2550 975);
PAINT RED (2550 975);
FORCEPROP 2 LAST CDS_LIB mstr_misc
J 0
(2550 975);
DISPLAY INVISIBLE (2550 975);
FORCEPROP 1 LAST COMMENT_BODY TRUE
R 1
J 0
(2625 750);
DISPLAY 0.872340 (2625 750);
PAINT GREEN (2625 750);
DISPLAY INVISIBLE (2625 750);
FORCEADD DNS..2
(3425 1500);
PAINT RED (3425 1500);
FORCEPROP 2 LAST CDS_LIB mstr_misc
J 0
(3425 1500);
DISPLAY INVISIBLE (3425 1500);
FORCEPROP 1 LAST COMMENT_BODY TRUE
R 1
J 0
(3500 1275);
DISPLAY 0.872340 (3500 1275);
PAINT GREEN (3500 1275);
DISPLAY INVISIBLE (3500 1275);
FORCEADD DNS..2
(3025 950);
PAINT RED (3025 950);
FORCEPROP 2 LAST CDS_LIB mstr_misc
J 0
(3025 950);
DISPLAY INVISIBLE (3025 950);
FORCEPROP 1 LAST COMMENT_BODY TRUE
R 1
J 0
(3100 725);
DISPLAY 0.872340 (3100 725);
PAINT GREEN (3100 725);
DISPLAY INVISIBLE (3100 725);
FORCEADD DNS..2
(9600 5350);
PAINT RED (9600 5350);
FORCEPROP 2 LAST CDS_LIB mstr_misc
J 0
(9600 5350);
DISPLAY INVISIBLE (9600 5350);
FORCEPROP 1 LAST COMMENT_BODY TRUE
R 1
J 0
(9675 5125);
DISPLAY 0.872340 (9675 5125);
PAINT GREEN (9675 5125);
DISPLAY INVISIBLE (9675 5125);
FORCEADD DNS..2
(7700 3225);
PAINT RED (7700 3225);
FORCEPROP 2 LAST CDS_LIB mstr_misc
J 0
(7700 3225);
DISPLAY INVISIBLE (7700 3225);
FORCEPROP 1 LAST COMMENT_BODY TRUE
R 1
J 0
(7775 3000);
DISPLAY 0.872340 (7775 3000);
PAINT GREEN (7775 3000);
DISPLAY INVISIBLE (7775 3000);
FORCEADD QUANTA_TITLE_BLOCK_C..1
(11050 100);
FORCEPROP 0 LAST CDS_CON_LAST_MODIFIED Thu Sep 14 16:12:36 2023
J 0
(9165 115);
DISPLAY INVISIBLE (9165 115);
FORCEPROP 1 LAST CUSTOM_TXT_CDS <CON_LAST_MODIFIED>
J 0
(9165 115);
DISPLAY 0.978723 (9165 115);
FORCEPROP 2 LAST CUSTOM_TXT_CDS <XR_PAGE_TITLE>
J 0
(3160 5350);
DISPLAY 0.638298 (3160 5350);
PAINT PINK (3160 5350);
DISPLAY INVISIBLE (3160 5350);
FORCEPROP 1 LAST CUSTOM_TXT_CDS <NAME_2>
J 0
(7875 150);
FORCEPROP 1 LAST CUSTOM_TXT_CDS <NAME_1>
J 0
(7875 275);
FORCEPROP 1 LAST CUSTOM_TXT_CDS <Q_NUMBER>
J 0
(9647 203);
DISPLAY 1.212766 (9647 203);
FORCEPROP 1 LAST CUSTOM_TXT_CDS <Q_PROJ>
J 0
(8668 202);
DISPLAY 1.212766 (8668 202);
FORCEPROP 1 LAST CUSTOM_TXT_CDS <Q_REV>
J 0
(10866 203);
DISPLAY 1.212766 (10866 203);
FORCEPROP 1 LAST CUSTOM_TXT_CDS <CON_PAGE_NUM> OF <CON_TOTAL_PAGES>
J 0
(10604 118);
DISPLAY 0.978723 (10604 118);
FORCEPROP 1 LAST Q_TITLE BMC - GPU FPGA PCIE - RE-DRIVER (main)
J 0
(1775 200);
DISPLAY 2.446809 (1775 200);
PAINT GREEN (1775 200);
FORCEPROP 2 LAST CDS_LIB pure_quanta
J 0
(11050 100);
DISPLAY INVISIBLE (11050 100);
FORCEPROP 1 LAST CDS_LMAN_SYM_OUTLINE -9475,6775,100,-125
J 0
(11050 100);
DISPLAY 0.468085 (11050 100);
PAINT GREEN (11050 100);
DISPLAY INVISIBLE (11050 100);
FORCEPROP 2 LAST PAGE_BORDER TRUE
J 0
(3160 5350);
DISPLAY 0.638298 (3160 5350);
PAINT PINK (3160 5350);
DISPLAY INVISIBLE (3160 5350);
FORCEPROP 2 LAST CDS_XR_PAGE_TITLE CR-111 : @T6G_MB_LIB.T6G(SCH_1):PAGE111
J 0
(3160 5350);
DISPLAY 0.638298 (3160 5350);
PAINT PINK (3160 5350);
DISPLAY INVISIBLE (3160 5350);
FORCEPROP 1 LAST Q_DEPT BU9
J 1
(7312 149);
DISPLAY 1.957447 (7312 149);
PAINT GREEN (7312 149);
DISPLAY INVISIBLE (7312 149);
FORCEPROP 1 LAST COMMENT_BODY TRUE
J 0
(11062 87);
DISPLAY 0.978723 (11062 87);
PAINT GREEN (11062 87);
DISPLAY INVISIBLE (11062 87);
WIRE 16 -1 (2175 700)(2175 900);
WIRE 16 -1 (2375 2425)(2375 2625);
WIRE 16 -1 (2850 2425)(2850 2600);
WIRE 16 -1 (3025 700)(3025 875);
WIRE 16 -1 (3425 700)(3425 850);
WIRE 16 -1 (4425 675)(4425 875);
WIRE 16 -1 (4800 675)(4800 875);
WIRE 16 -1 (3250 2425)(3250 2575);
WIRE 16 -1 (2550 700)(2550 900);
WIRE 16 -1 (5275 675)(5275 850);
WIRE 16 -1 (5675 675)(5675 825);
WIRE 16 -1 (6450 2425)(6450 2625);
WIRE 16 -1 (6825 2425)(6825 2625);
WIRE 16 -1 (2000 2425)(2000 2625);
WIRE 16 -1 (7300 2425)(7300 2600);
WIRE 16 -1 (7700 2425)(7700 2575);
WIRE 16 -1 (9575 3750)(9575 3825);
WIRE 16 -1 (8350 4725)(8350 4800);
WIRE 16 -1 (9600 5200)(9600 5275);
WIRE 16 -1 (9575 4550)(9575 4700);
WIRE 16 -1 (9600 6000)(9600 6150);
WIRE 16 -1 (4625 5575)(4750 5575);
WIRE 16 -1 (4625 5625)(4625 5575);
WIRE 16 -1 (4625 5675)(4625 5625);
WIRE 16 -1 (4750 5625)(4625 5625);
WIRE 16 -1 (4750 5675)(4625 5675);
WIRE 16 -1 (4625 5725)(4625 5675);
WIRE 16 -1 (4625 6100)(4625 5725);
WIRE 16 -1 (4750 5725)(4625 5725);
WIRE 16 -1 (4625 6225)(4625 6100);
WIRE 16 -1 (4625 6100)(4225 6100);
WIRE 16 -1 (4225 5975)(4225 6100);
WIRE 16 -1 (4225 6100)(3750 6100);
WIRE 16 -1 (3750 6100)(3750 5975);
WIRE 16 -1 (3750 6100)(3275 6100);
WIRE 16 -1 (3275 6100)(3275 5975);
WIRE 16 -1 (3275 6100)(2825 6100);
WIRE 16 -1 (2825 6100)(2825 5975);
WIRE 16 -1 (2825 6100)(2275 6100);
WIRE 16 -1 (2275 5975)(2275 6100);
WIRE 16 -1 (3250 2900)(3250 2950);
WIRE 16 -1 (3250 2775)(3250 2900);
WIRE 16 -1 (3250 2900)(2850 2900);
WIRE 16 -1 (3250 3150)(3250 2950);
WIRE 16 -1 (3250 2950)(3650 2950);
FORCEPROP 2 LAST SIG_NAME FM_P2E_FGA
J 0
(3290 2960);
DISPLAY 0.638298 (3290 2960);
PAINT WHITE (3290 2960);
WIRE 16 -1 (2850 2900)(2850 2800);
WIRE 16 -1 (6625 5525)(5650 5525);
FORCEPROP 2 LAST SIG_NAME P2E_MB_BMC_RX_BUF_C_DP<0>
J 0
(5815 5535);
DISPLAY 0.553191 (5815 5535);
PAINT WHITE (5815 5535);
WIRE 16 -1 (4750 4575)(3550 4575);
FORCEPROP 2 LAST SIG_NAME P2E_MB_BMC_RX_R1_DN<0>
J 0
(3824 4585);
DISPLAY 0.553191 (3824 4585);
PAINT WHITE (3824 4585);
WIRE 16 -1 (4750 4925)(3550 4925);
FORCEPROP 2 LAST SIG_NAME FM_P2E_EQB0
J 0
(3815 4935);
DISPLAY 0.553191 (3815 4935);
PAINT WHITE (3815 4935);
WIRE 16 -1 (4750 4875)(3550 4875);
FORCEPROP 2 LAST SIG_NAME FM_P2E_EQB1
J 0
(3815 4885);
DISPLAY 0.553191 (3815 4885);
PAINT WHITE (3815 4885);
WIRE 16 -1 (4750 4625)(3550 4625);
FORCEPROP 2 LAST SIG_NAME P2E_MB_BMC_RX_R1_DP<0>
J 0
(3824 4635);
DISPLAY 0.553191 (3824 4635);
PAINT WHITE (3824 4635);
WIRE 16 -1 (6625 5475)(5650 5475);
FORCEPROP 2 LAST SIG_NAME P2E_MB_BMC_RX_BUF_C_DN<0>
J 0
(5815 5485);
DISPLAY 0.553191 (5815 5485);
PAINT WHITE (5815 5485);
WIRE 16 -1 (6150 5025)(5650 5025);
FORCEPROP 2 LAST SIG_NAME FM_P2E_EN_N
J 0
(5815 5035);
DISPLAY 0.553191 (5815 5035);
PAINT WHITE (5815 5035);
FORCEPROP 2 LASTPROP $XRERR UNIQUE?
J 0
(5575 5035);
DISPLAY 0.638298 (5575 5035);
PAINT MONO (5575 5035);
DISPLAY INVISIBLE (5575 5035);
WIRE 16 -1 (6550 5325)(5650 5325);
FORCEPROP 2 LAST SIG_NAME FM_P2E_MODE
J 0
(5810 5335);
DISPLAY 0.553191 (5810 5335);
PAINT WHITE (5810 5335);
WIRE 16 -1 (9600 5475)(9600 5650);
WIRE 16 -1 (9600 5650)(10275 5650);
FORCEPROP 2 LAST SIG_NAME FM_P2E_MODE
J 0
(9840 5660);
DISPLAY 0.680851 (9840 5660);
PAINT WHITE (9840 5660);
WIRE 16 -1 (9600 5650)(9600 5800);
WIRE 16 -1 (9575 4025)(9575 4225);
WIRE 16 -1 (9575 4225)(10675 4225);
FORCEPROP 2 LAST SIG_NAME CLK_GEN2_GPU_FPGA_OE_OR_N
J 0
(9815 4235);
DISPLAY 0.680851 (9815 4235);
PAINT WHITE (9815 4235);
WIRE 16 -1 (9575 4225)(9575 4350);
WIRE 16 -1 (6350 5025)(7575 5025);
FORCEPROP 2 LAST SIG_NAME CLK_GEN2_GPU_FPGA_OE_OR_N
J 0
(6740 5035);
DISPLAY 0.680851 (6740 5035);
PAINT WHITE (6740 5035);
WIRE 16 -1 (4750 4725)(3550 4725);
FORCEPROP 2 LAST SIG_NAME P2E_MB_BMC_TX_C_R1_DN<0>
J 0
(3815 4735);
DISPLAY 0.553191 (3815 4735);
PAINT WHITE (3815 4735);
WIRE 16 -1 (4750 4775)(3550 4775);
FORCEPROP 2 LAST SIG_NAME P2E_MB_BMC_TX_C_R1_DP<0>
J 0
(3815 4785);
DISPLAY 0.553191 (3815 4785);
PAINT WHITE (3815 4785);
WIRE 16 -1 (2375 2950)(2375 3000);
WIRE 16 -1 (2375 2825)(2375 2950);
WIRE 16 -1 (2375 2950)(2000 2950);
WIRE 16 -1 (2375 3000)(3650 3000);
FORCEPROP 2 LAST SIG_NAME FM_P2E_FGB
J 0
(3290 3010);
DISPLAY 0.638298 (3290 3010);
PAINT WHITE (3290 3010);
WIRE 16 -1 (2375 3000)(2375 3150);
WIRE 16 -1 (2000 2950)(2000 2825);
WIRE 16 -1 (2550 1225)(2550 1275);
WIRE 16 -1 (2550 1100)(2550 1225);
WIRE 16 -1 (2550 1225)(2175 1225);
WIRE 16 -1 (2550 1275)(3900 1275);
FORCEPROP 2 LAST SIG_NAME FM_P2E_EQA1
J 0
(3465 1285);
DISPLAY 0.638298 (3465 1285);
PAINT WHITE (3465 1285);
WIRE 16 -1 (2550 1275)(2550 1425);
WIRE 16 -1 (2175 1225)(2175 1100);
WIRE 16 -1 (3425 1050)(3425 1200);
WIRE 16 -1 (3425 1200)(3425 1225);
WIRE 16 -1 (3425 1200)(3025 1200);
WIRE 16 -1 (3025 1200)(3025 1075);
WIRE 16 -1 (3425 1225)(3900 1225);
FORCEPROP 2 LAST SIG_NAME FM_P2E_EQA0
J 0
(3465 1235);
DISPLAY 0.638298 (3465 1235);
PAINT WHITE (3465 1235);
WIRE 16 -1 (3425 1425)(3425 1225);
WIRE 16 -1 (5675 1175)(5675 1200);
WIRE 16 -1 (5675 1025)(5675 1175);
WIRE 16 -1 (5675 1175)(5275 1175);
WIRE 16 -1 (5675 1200)(6125 1200);
FORCEPROP 2 LAST SIG_NAME FM_P2E_EQB0
J 0
(5715 1210);
DISPLAY 0.638298 (5715 1210);
PAINT WHITE (5715 1210);
WIRE 16 -1 (5675 1400)(5675 1200);
WIRE 16 -1 (5275 1175)(5275 1050);
WIRE 16 -1 (4800 1200)(4800 1250);
WIRE 16 -1 (4800 1075)(4800 1200);
WIRE 16 -1 (4800 1200)(4425 1200);
WIRE 16 -1 (4800 1250)(6125 1250);
FORCEPROP 2 LAST SIG_NAME FM_P2E_EQB1
J 0
(5715 1260);
DISPLAY 0.638298 (5715 1260);
PAINT WHITE (5715 1260);
WIRE 16 -1 (4800 1250)(4800 1400);
WIRE 16 -1 (4425 1200)(4425 1075);
WIRE 16 -1 (3250 3350)(3250 3450);
WIRE 16 -1 (3250 3450)(2375 3450);
WIRE 16 -1 (2375 3500)(2375 3450);
WIRE 16 -1 (2375 3450)(2375 3350);
WIRE 16 -1 (5675 1600)(5675 1700);
WIRE 16 -1 (5675 1700)(4800 1700);
WIRE 16 -1 (4800 1750)(4800 1700);
WIRE 16 -1 (4800 1700)(4800 1600);
WIRE 16 -1 (5725 4875)(5650 4875);
WIRE 16 -1 (5725 4875)(5725 4825);
WIRE 16 -1 (5725 4825)(5725 4775);
WIRE 16 -1 (5725 4825)(5650 4825);
WIRE 16 -1 (5725 4775)(5650 4775);
WIRE 16 -1 (5725 4775)(5725 4725);
WIRE 16 -1 (5725 4725)(5725 4675);
WIRE 16 -1 (5725 4725)(5650 4725);
WIRE 16 -1 (5725 4675)(5725 4625);
WIRE 16 -1 (5725 4675)(5650 4675);
WIRE 16 -1 (5725 4625)(5650 4625);
WIRE 16 -1 (5725 4625)(5725 4575);
WIRE 16 -1 (5725 4575)(5650 4575);
WIRE 16 -1 (5725 4375)(5725 4575);
WIRE 16 -1 (5650 4375)(5725 4375);
WIRE 16 -1 (5725 4200)(5725 4375);
WIRE 16 -1 (3425 1625)(3425 1725);
WIRE 16 -1 (3425 1725)(2550 1725);
WIRE 16 -1 (2550 1775)(2550 1725);
WIRE 16 -1 (2550 1725)(2550 1625);
WIRE 16 -1 (8350 5000)(8350 5175);
WIRE 16 -1 (8350 5175)(5650 5175);
FORCEPROP 2 LAST SIG_NAME PU_TEST
J 0
(5820 5185);
DISPLAY 0.553191 (5820 5185);
PAINT WHITE (5820 5185);
FORCEPROP 2 LASTPROP $XRERR UNIQUE?
J 0
(5580 5185);
DISPLAY 0.638298 (5580 5185);
PAINT MONO (5580 5185);
DISPLAY INVISIBLE (5580 5185);
WIRE 16 -1 (7700 2900)(7700 2950);
WIRE 16 -1 (7700 2775)(7700 2900);
WIRE 16 -1 (7700 2900)(7300 2900);
WIRE 16 -1 (7700 3150)(7700 2950);
WIRE 16 -1 (7700 2950)(8125 2950);
FORCEPROP 2 LAST SIG_NAME FM_P2E_SWA
J 0
(7740 2960);
DISPLAY 0.638298 (7740 2960);
PAINT WHITE (7740 2960);
WIRE 16 -1 (7300 2900)(7300 2800);
WIRE 16 -1 (4750 5025)(3550 5025);
FORCEPROP 2 LAST SIG_NAME FM_P2E_EQA1
J 0
(3815 5035);
DISPLAY 0.553191 (3815 5035);
PAINT WHITE (3815 5035);
WIRE 16 -1 (4750 5075)(3550 5075);
FORCEPROP 2 LAST SIG_NAME FM_P2E_EQA0
J 0
(3815 5085);
DISPLAY 0.553191 (3815 5085);
PAINT WHITE (3815 5085);
WIRE 16 -1 (4750 5175)(3550 5175);
FORCEPROP 2 LAST SIG_NAME FM_P2E_SWB
J 0
(3815 5185);
DISPLAY 0.553191 (3815 5185);
PAINT WHITE (3815 5185);
WIRE 16 -1 (4750 5225)(3550 5225);
FORCEPROP 2 LAST SIG_NAME FM_P2E_SWA
J 0
(3815 5235);
DISPLAY 0.553191 (3815 5235);
PAINT WHITE (3815 5235);
WIRE 16 -1 (4750 5375)(3550 5375);
FORCEPROP 2 LAST SIG_NAME FM_P2E_FGB
J 0
(3815 5385);
DISPLAY 0.553191 (3815 5385);
PAINT WHITE (3815 5385);
WIRE 16 -1 (4750 5425)(3550 5425);
FORCEPROP 2 LAST SIG_NAME FM_P2E_FGA
J 0
(3815 5435);
DISPLAY 0.553191 (3815 5435);
PAINT WHITE (3815 5435);
WIRE 16 -1 (2275 5775)(2275 5650);
WIRE 16 -1 (2275 5650)(2700 5650);
WIRE 16 -1 (2825 5650)(2700 5650);
WIRE 16 -1 (2700 5600)(2700 5650);
WIRE 16 -1 (3275 5650)(2825 5650);
WIRE 16 -1 (2825 5650)(2825 5775);
WIRE 16 -1 (3750 5650)(3275 5650);
WIRE 16 -1 (3275 5650)(3275 5775);
WIRE 16 -1 (4225 5650)(3750 5650);
WIRE 16 -1 (3750 5650)(3750 5775);
WIRE 16 -1 (4225 5775)(4225 5650);
WIRE 16 -1 (6625 5675)(5650 5675);
FORCEPROP 2 LAST SIG_NAME P2E_MB_BMC_TX_BUF_DN<0>
J 0
(5815 5685);
DISPLAY 0.553191 (5815 5685);
PAINT WHITE (5815 5685);
WIRE 16 -1 (6625 5725)(5650 5725);
FORCEPROP 2 LAST SIG_NAME P2E_MB_BMC_TX_BUF_DP<0>
J 0
(5815 5735);
DISPLAY 0.553191 (5815 5735);
PAINT WHITE (5815 5735);
WIRE 16 -1 (6825 2950)(6825 3000);
WIRE 16 -1 (6825 2825)(6825 2950);
WIRE 16 -1 (6825 2950)(6450 2950);
WIRE 16 -1 (6825 3000)(8125 3000);
FORCEPROP 2 LAST SIG_NAME FM_P2E_SWB
J 0
(7740 3010);
DISPLAY 0.638298 (7740 3010);
PAINT WHITE (7740 3010);
WIRE 16 -1 (6825 3000)(6825 3150);
WIRE 16 -1 (6450 2950)(6450 2825);
WIRE 16 -1 (7700 3350)(7700 3450);
WIRE 16 -1 (7700 3450)(6825 3450);
WIRE 16 -1 (6825 3500)(6825 3450);
WIRE 16 -1 (6825 3450)(6825 3350);
DOT 1 (2825 6100);
DOT 1 (2375 3450);
DOT 1 (3250 2950);
DOT 1 (5725 4825);
DOT 1 (9600 5650);
DOT 1 (9575 4225);
DOT 1 (7700 2900);
DOT 1 (5725 4725);
DOT 1 (5725 4625);
DOT 1 (5725 4575);
DOT 1 (5725 4375);
DOT 1 (4625 6100);
DOT 1 (4625 5625);
DOT 1 (6825 3450);
DOT 1 (6825 2950);
DOT 1 (5675 1175);
DOT 1 (3250 2900);
DOT 1 (4800 1700);
DOT 1 (4800 1200);
DOT 1 (3425 1200);
DOT 1 (2375 2950);
DOT 1 (2375 3000);
DOT 1 (2550 1725);
DOT 1 (2550 1275);
DOT 1 (2550 1225);
DOT 1 (2700 5650);
DOT 1 (2825 5650);
DOT 1 (3275 6100);
DOT 1 (3275 5650);
DOT 1 (3750 6100);
DOT 1 (4225 6100);
DOT 1 (4625 5725);
DOT 1 (4625 5675);
DOT 1 (5725 4675);
DOT 1 (5725 4775);
DOT 1 (3425 1225);
DOT 1 (4800 1250);
DOT 1 (5675 1200);
DOT 1 (6825 3000);
DOT 1 (7700 2950);
DOT 1 (3750 5650);
FORCENOTE
$CDS_IMAGE|clipboard_0_26.jpg|2096|590
(5175 3050) 0;
DISPLAY LEFT (5175 3050);
FORCENOTE
$CDS_IMAGE|clipboard_2_9.jpg|3100|1783
(8175 1325) 0;
DISPLAY LEFT (8175 1325);
FORCENOTE
$CDS_IMAGE|clipboard_1_15.jpg|2443|662
(9750 2975) 0;
DISPLAY LEFT (9750 2975);
QUIT
